# Barreleye-G2_Tri-mode Expander-DVT-X01-SKU-BOM-X07-20171222_Final.xls.xlsx — SKU2 (bom)
| FOXCONN TECHNOLOGY GROUP |  |  |  |  |  |  |  |  |  |  |  |  |  |  |  |  |  |  |  |
| BILL OF MATERIAL |  |  |  |  |  |  |  |  |  |  |  |  |  |  |  |  |  |  |  |
| REV OF  BOM |  | CUSTOMER |  | <name> |  | CUSTOMER P/N |  | AA P/N：1A42NC400-600-2 | PWA DESCRIPTION |  |  |  | PRODUCT CODE |  |  | PWA  REV |  | DATE |  |
| Sourcing (Single/Sole/Multi) | Critical Commodity (Y or N) | Component Class (1, 2, other) | Customer PSL (Y or N) | Line Item | Item Number | Foxconn P/N | Customer P/N | Part Description | Manufacturer  Full Name | Manufacturer  Part Number | Qty | RoHS Status | Location | CC Qual Build: | Qual by (Customer / ODM ?) | The Date of Change Part or Add 2nd Source | Configuration Identifier | Customer Comments | ODM Comments |
|  |  |  |  | 1 | 1 | 0101FGB00-000-G |  | PCB,Zaius-Tri-mode Expander DVT-X01,Blu,10L,9.134*5.118,G | GOLD CIRCUIT ELECTRONICS LTD. | 0101FGB00-000-G | 1 | G | PCB |  |  |  |  |  |  |
|  |  |  |  |  | 1 | 0101FGB00-000-G |  | PCB,Zaius-Tri-mode Expander DVT-X01,Blu,10L,9.134*5.118,G | ZHUHAI FOUNDER PRINTED CIRCUIT BOARD（HK） DEVELOPMENT LIMITED | 0101FGB00-000-G |  | G |  |  |  |  |  |  |  |
|  |  |  |  | 2 | 2 | 62110EH00-024-G |  | ECAP,680uF,+/-20%,16V,105_x0003_,G,SMD10X10.2,ESR<=80mOhm | PANASONIC INDUSTRIAL CO.,LTD. | EEEFK1C681P | 2 | G | CE1,CE2 |  |  |  |  |  |  |
|  |  |  |  | 3 | 3 | 620101T02-015-G | - | CAP,100nF,+/-10%,X7R,16V,G,SMD0402 | MURATA ELEC. NORTH AMERICA | GRM155R71C104K | 35 | G | PSCC1,C1,PFCC2,PELC2,PLTC5,C8,PSRC10,PLTC11,PELC11,PFCC13,PECC15,PECC16,PECC18,PECC19,C223,C225,C226,C229,C231,C393,C394,C395,C396,C397,C411,C413,C610,C611,C612,C968,C970,C1524,C2004,C2180,C2183 |  |  |  |  |  |  |
|  |  |  |  |  | 3 | 620101T00-012-G |  | CAP,100nF,+/-10%,X7R,16V,G,SMD0402 | WALSIN TECHNOLOGY CORPORATION | 0402B104K160CT |  | G |  |  |  |  |  |  |  |
|  |  |  |  |  | 3 | 620101T00-026-G |  | CAP,100nF,+/-10%,X7R,16V,G,SMD0402 | SAMSUNG SEMICONDUCTOR | CL05B104KO5NNNC |  | G |  |  |  |  |  |  |  |
|  |  |  |  |  | 3 | 620101T00-015-G |  | CAP,100nF,+/-10%,X7R,16V,G,SMD0402 | MURATA ELEC. NORTH AMERICA | GRM155R71C104KA88D |  | G |  |  |  |  |  |  |  |
|  |  |  |  | 4 | 4 | 62010BN00-015-G | - | CAP,1uF,+/-10%,X5R,6.3V,G,SMD0402 | MURATA ELEC. NORTH AMERICA | GRM155R60J105K | 3 | G | C2,C4,C5 |  |  |  |  |  |  |
|  |  |  |  |  | 4 | 62010BN00-011-G |  | CAP,1uF,+/-10%,X5R,6.3V,G,SMD0402 | YAGEO CORPORATION COMPONENT | CC0402KRX5R5BB105 |  | G |  |  |  |  |  |  |  |
|  |  |  |  |  | 4 | 62010BN00-012-G |  | CAP,1uF,+/-10%,X5R,6.3V,G,SMD0402 | WALSIN TECHNOLOGY CORPORATION | 0402X105K6R3CT |  | G |  |  |  |  |  |  |  |
|  |  |  |  |  | 4 | 62010BN00-026-G |  | CAP,1uF,+/-10%,X5R,6.3V,G,SMD0402 | SAMSUNG SEMICONDUCTOR | CL05A105KQ5NNNC |  | G |  |  |  |  |  |  |  |
|  |  |  |  |  | 4 | 62010BN00-023-G |  | CAP,1uF,+/-10%,X5R,6.3V,G,SMD0402 | TAIYO ELECTRIC IND.CO.LTD | JMK105BJ105KV |  | G |  |  |  |  |  |  |  |
|  |  |  |  | 5 | 5 | 620106200-015-G | - | CAP,10nF,+/-10%,X7R,16V,G,SMD0402 | MURATA ELEC. NORTH AMERICA | GRM155R71C103K | 33 | G | C3,C6,C7,C25,C30,C39,C44,C49,C54,C61,C62,C69,C70,C77,C78,C85,C86,C93,C94,C101,C102,C109,C110,C117,C118,C125,C126,C133,C134,C141,C142,C149,C150 |  |  |  |  |  |  |
|  |  |  |  |  | 5 | 620106200-012-G |  | CAP,10nF,+/-10%,X7R,16V,G,SMD0402 | WALSIN TECHNOLOGY CORPORATION | 0402B103K160CT |  | G |  |  |  |  |  |  |  |
|  |  |  |  |  | 5 | 620106200-026-G |  | CAP,10nF,+/-10%,X7R,16V,G,SMD0402 | SAMSUNG SEMICONDUCTOR | CL05B103KO5NNNC |  | G |  |  |  |  |  |  |  |
|  |  |  |  |  | 5 | 620106200-023-G |  | CAP,10nF,+/-10%,X7R,16V,G,SMD0402 | TAIYO ELECTRIC IND.CO.LTD | EMK105B7103KV-F |  | G |  |  |  |  |  |  |  |
|  |  |  |  | 6 | 6 | 620108H00-015-G | - | CAP,22uF,+/-20%,X5R,6.3V,G,SMD0805 | MURATA ELEC. NORTH AMERICA | GRM21BR60J226M | 10 | G | C9,C13,C17,C21,C26,C31,C35,C40,C45,C50 |  |  |  |  |  |  |
|  |  |  |  |  | 6 | 620108H04-023-G |  | CAP,22uF,+/-20%,X5R,6.3V,G,SMD0805 | TAIYO ELECTRIC IND.CO.LTD | JMK212BJ226MG-T |  | G |  |  |  |  |  |  |  |
|  |  |  |  |  | 6 | 620108H00-026-G |  | CAP,22uF,+/-20%,X5R,6.3V,G,SMD0805 | SAMSUNG SEMICONDUCTOR | CL21A226MQQNNNE |  | G |  |  |  |  |  |  |  |
|  |  |  |  |  | 6 | 620108H00-011-G |  | CAP,22uF,+/-20%,X5R,6.3V,G,SMD0805 | YAGEO CORPORATION COMPONENT | CC0805MKX5R5BB226 |  | G |  |  |  |  |  |  |  |
|  |  |  |  | 7 | 7 | 62010L000-015-G | - | CAP,10uF,+/-20%,X5R,6.3V,G,SMD0603 | MURATA ELEC. NORTH AMERICA | GRM188R60J106M | 23 | G | C10,C14,C18,C22,C27,C32,C36,C41,C46,C51,C151,C152,C153,C154,C155,C191,C192,C193,C194,C224,C227,C228,C230 |  |  |  |  |  |  |
|  |  |  |  |  | 7 | 62010L000-023-G |  | CAP,10uF,+/-20%,X5R,6.3V,G,SMD0603 | TAIYO ELECTRIC IND.CO.LTD | JMK107BJ106MA-T |  | G |  |  |  |  |  |  |  |
|  |  |  |  |  | 7 | 62010L000-012-G |  | CAP,10uF,+/-20%,X5R,6.3V,G,SMD0603 | WALSIN TECHNOLOGY CORPORATION | 0603X106M6R3CT |  | G |  |  |  |  |  |  |  |
|  |  |  |  |  | 7 | 62010L000-026-G |  | CAP,10uF,+/-20%,X5R,6.3V,G,SMD0603 | SAMSUNG SEMICONDUCTOR | CL10A106MQ8NNNC |  | G |  |  |  |  |  |  |  |
|  |  |  |  |  | 7 | 62010L000-011-G |  | CAP,10uF,+/-20%,X5R,6.3V,G,SMD0603 | YAGEO CORPORATION COMPONENT | CC0603MRX5R5BB106 |  | G |  |  |  |  |  |  |  |
|  |  |  |  | 8 | 8 | 62012NU00-015-G | - | CAP,1uF,+/-10%,X7R,6.3V,G,SMD0402 | MURATA ELEC. NORTH AMERICA | GRM155R70J105KA12D | 22 | G | C11,C15,C19,C23,C28,C33,C37,C42,C47,C52,C57,C65,C73,C81,C89,C97,C105,C113,C121,C129,C137,C145 |  |  |  |  |  |  |
|  |  |  |  |  | 8 | 62012NU00-026-G |  | CAP,1uF,+/-10%,X7R,6.3V,G,SMD0402 | SAMSUNG SEMICONDUCTOR | CL05B105KQ5NQNC |  | G |  |  |  |  |  |  |  |
|  |  |  |  | 9 | 9 | 620103700-015-G | - | CAP,100nF,+/-10%,X7R,10V,G,SMD0402 | MURATA ELEC. NORTH AMERICA | GRM155R71A104K | 106 | G | PSLC10,PSGC10,C12,C16,C20,C24,C29,C34,C38,C43,C48,C53,C58,C59,C60,C66,C67,C68,C74,C75,C76,C82,C83,C84,C90,C91,C92,C98,C99,C100,C106,C107,C108,C114,C115,C116,C122,C123,C124,C130,C131,C132,C138,C139,C140,C146,C147,C148,C161,C162,C163,C164,C165,C166,C167,C168,C169,C170,C171,C172,C173,C174,C175,C176,C177,C178,C179,C180,C181,C182,C183,C184,C185,C186,C187,C188,C189,C190,C199,C200,C201,C202,C203,C204,C205,C206,C207,C208,C209,C210,C211,C212,C213,C214,C215,C216,C217,C218,C219,C220,C221,C222,C415,C2179,C2181,C2182 |  |  |  |  |  |  |
|  |  |  |  |  | 9 | 620103700-012-G |  | CAP,0.1uF,+/-10%,X7R,10V,G,SMD0402 | WALSIN TECHNOLOGY CORPORATION | 0402B104K100CT |  | G |  |  |  |  |  |  |  |
|  |  |  |  |  | 9 | 620103700-023-G |  | CAP,100nF,+/-10%,X7R,10V,G,SMD0402 | TAIYO ELECTRIC IND.CO.LTD | LMK105B7104KV-F |  | G |  |  |  |  |  |  |  |
|  |  |  |  |  | 9 | 620103700-026-G |  | CAP,100nF,+/-10%,X7R,10V,G,SMD0402 | SAMSUNG SEMICONDUCTOR | CL05B104KP5NNNC |  | G |  |  |  |  |  |  |  |
|  |  |  |  | 10 | 10 | 620132700-015-G |  | CAP,100uF,+/-20%,X5R,6.3V,G,SMD0805 | MURATA ELEC. NORTH AMERICA | GRM21BR60J107ME15L | 12 | G | C55,C63,C71,C79,C87,C95,C103,C111,C119,C127,C135,C143 |  |  |  |  |  |  |
|  |  |  |  |  | 10 | 620132700-012-G |  | CAP,100uF,+/-20%,X5R,6.3V,G,SMD0805 | WALSIN TECHNOLOGY CORPORATION | 0805X107M6R3CT |  | G |  |  |  |  |  |  |  |
|  |  |  |  | 11 | 11 | 62012Y400-015-G |  | CAP,22uF,+/-20%,X5R,6.3V,G,SMD0402 | MURATA ELEC. NORTH AMERICA | GRM155R60J226ME11D | 12 | G | C56,C64,C72,C80,C88,C96,C104,C112,C120,C128,C136,C144 |  |  |  |  |  |  |
|  |  |  |  |  | 11 | 62012Y400-026-G |  | CAP,22uF,+/-20%,X5R,6.3V,G,SMD0402 | SAMSUNG SEMICONDUCTOR | CL05A226MQ5N6J8 |  | G |  |  |  |  |  |  |  |
|  |  |  |  |  | 11 | 62012Y400-011-G |  | CAP,22uF,+/-20%,X5R,6.3V,G,SMD0402 | YAGEO CORPORATION COMPONENT | CC0402MRX5R5BB226 |  | G |  |  |  |  |  |  |  |
|  |  |  |  |  | 11 | 62012Y400-012-G |  | CAP,22uF,+/-20%,X5R,6.3V,G,SMD0402 | WALSIN TECHNOLOGY CORPORATION | 0402X226M6R3CT |  | G |  |  |  |  |  |  |  |
|  |  |  |  | 12 | 12 | 62010P501-015-G | - | CAP,1nF,+/-10%,X7R,16V,G,SMD0402 | MURATA ELEC. NORTH AMERICA | GRM155R71C102KA01D | 9 | G | C156,C157,C158,C159,C160,C195,C196,C197,C198 |  |  |  |  |  |  |
|  |  |  |  |  | 12 | 62010P500-023-G |  | CAP,1nF,+/-10%,X7R,16V,G,SMD0402 | TAIYO ELECTRIC IND.CO.LTD | EMK105B7102KV-F |  | G |  |  |  |  |  |  |  |
|  |  |  |  |  | 12 | 62010P500-026-G |  | CAP,1nF,+/-10%,X7R,16V,G,SMD0402 | SAMSUNG SEMICONDUCTOR | CL05B102KO5NNNC |  | G |  |  |  |  |  |  |  |
|  |  |  |  | 13 | 13 | 62012QF00-023-G |  | CAP,10nF,+/-10%,X7R,16V,G,SMD0201 | TAIYO ELECTRIC IND.CO.LTD | EMK063B7103KP-F | 212 | G | C233,C234,C235,C236,C237,C238,C239,C240,C241,C242,C243,C244,C245,C246,C247,C248,C249,C250,C251,C252,C253,C254,C255,C256,C257,C258,C259,C260,C261,C262,C263,C264,C297,C298,C299,C300,C301,C302,C303,C304,C305,C306,C307,C308,C309,C310,C311,C312,C313,C314,C315,C316,C317,C318,C319,C320,C321,C322,C323,C324,C325,C326,C327,C328,C329,C330,C331,C332,C333,C334,C335,C336,C337,C338,C339,C340,C341,C342,C343,C344,C345,C346,C347,C348,C349,C350,C351,C352,C353,C354,C355,C356,C357,C358,C359,C360,C361,C362,C363,C364,C365,C366,C367,C368,C369,C370,C371,C372,C373,C374,C375,C376,C377,C378,C379,C380,C381,C382,C383,C384,C385,C386,C387,C388,C389,C390,C391,C392,C640,C641,C642,C643,C644,C645,C646,C647,C648,C649,C650,C651,C652,C653,C654,C655,C656,C657,C658,C659,C660,C661,C662,C663,C664,C665,C674,C675,C676,C677,C678,C679,C680,C681,C682,C725,C726,C727,C728,C729,C730,C731,C732,C733,C734,C735,C736,C737,C738,C739,C740,C741,C742,C743,C744,C745,C746,C747,C748,C749,C750,C751,C752,C753,C754,C755,C756,C757,C758,C759,C775,C776,C777,C778,C779,C780,C781,C797,C798,C799,C800,C801,C802,C803 |  |  |  |  |  |  |
|  |  |  |  |  | 13 | 62012QF00-012-G |  | CAP,10nF,+/-10%,X7R,16V,G,SMD0201 | WALSIN TECHNOLOGY CORPORATION | 0201B103K160CT |  | G |  |  |  |  |  |  |  |
|  |  |  |  |  | 13 | 62012QF00-026-G |  | CAP,10nF,+/-10%,X7R,16V,G,SMD0201 | SAMSUNG SEMICONDUCTOR | CL03B103KO3NNNC |  | G |  |  |  |  |  |  |  |
|  |  |  |  | 14 | 14 | 62012GG00-015-G | - | CAP,10uF,+/-10%,X7S,25V,G,SMD0805 | MURATA ELEC. NORTH AMERICA | GRM21BC71E106K | 7 | G | PLTC1,PSRC3,PSLC3,PSGC3,C398,C399,PSCC3004 |  |  |  |  |  |  |
|  |  |  |  |  | 14 | 62012GG00-012-G |  | CAP,10uF,+/-10%,X7S,25V,G,SMD0805 | WALSIN TECHNOLOGY CORPORATION | 0805A106K250CT |  | G |  |  |  |  |  |  |  |
|  |  |  |  | 15 | 15 | 62012A400-015-G | - | CAP,100nF,+/-10%,X7R,25V,G,SMD0402 | MURATA ELEC. NORTH AMERICA | GRM155R71E104KE14D | 17 | G | PSRC1,PSLC1,PSGC1,PELC3,PLTC4,PFCC4,PELC4,PSRC6,PSLC6,PSGC6,PELC10,PFCC11,PECC13,C400,C404,PSCC3002,PSCC3008 |  |  |  |  |  |  |
|  |  |  |  |  | 15 | 62012A400-023-G |  | CAP,100nF,+/-10%,X7R,25V,G,SMD0402 | TAIYO ELECTRIC IND.CO.LTD | TMK105B7104KV-FR |  | G |  |  |  |  |  |  |  |
|  |  |  |  |  | 15 | 62012A400-026-G |  | CAP,100nF,+/-10%,X7R,25V,G,SMD0402 | SAMSUNG SEMICONDUCTOR | CL05B104KA5NNNC |  | G |  |  |  |  |  |  |  |
|  |  |  |  |  | 15 | 62012A400-012-G |  | CAP,100nF,+/-10%,X7R,25V,G,SMD0402 | WALSIN TECHNOLOGY CORPORATION | 0402B104K250CT |  | G |  |  |  |  |  |  |  |
|  |  |  |  | 16 | 16 | 620109N00-015-G |  | CAP,2.2uF,+/-10%,X7R,10V,G,SMD0603 | MURATA ELEC. NORTH AMERICA | GRM188R71A225K | 1 | G | C401 |  |  |  |  |  |  |
|  |  |  |  |  | 16 | 620109N00-023-G |  | CAP,2.2uF,+/-10%,X7R,10V,G,SMD0603 | TAIYO ELECTRIC IND.CO.LTD | LMK107B7225KA-T |  | G |  |  |  |  |  |  |  |
|  |  |  |  |  | 16 | 620109N00-026-G |  | CAP,2.2uF,+/-10%,X7R,10V,G,SMD0603 | SAMSUNG SEMICONDUCTOR | CL10B225KP8NNNC |  | G |  |  |  |  |  |  |  |
|  |  |  |  | 17 | 17 | 62012H100-015-G | - | CAP,10uF,+/-20%,X6S,10V,G,SMD0603 | MURATA ELEC. NORTH AMERICA | GRM188C81A106M | 3 | G | PSRC16,C402,C403 |  |  |  |  |  |  |
|  |  |  |  |  | 17 | 62012H100-023-G |  | CAP,10uF,+/-20%,X6S,10V,G,SMD0603 | TAIYO ELECTRIC IND.CO.LTD | LMK107BC6106MA-T |  | G |  |  |  |  |  |  |  |
|  |  |  |  |  | 17 | 62012H100-026-G |  | CAP,10uF,+/-20%,X6S,10V,G,SMD0603 | SAMSUNG SEMICONDUCTOR | CL10X106MP8NRNC |  | G |  |  |  |  |  |  |  |
|  |  |  |  | 18 | 18 | 620108J00-015-G | - | CAP,100uF,+/-20%,X5R,6.3V,G,SMD1210 | MURATA ELEC. NORTH AMERICA | GRM32ER60J107M | 1 | G | C406 |  |  |  |  |  |  |
|  |  |  |  |  | 18 | 620108J00-012-G |  | CAP,100uF,+/-20%,X5R,6.3V,G,SMD1210 | WALSIN TECHNOLOGY CORPORATION | 1210X107M6R3CT |  | G |  |  |  |  |  |  |  |
|  |  |  |  |  | 18 | 620108J00-011-G |  | CAP,100uF,+/-20%,X5R,6.3V,G,SMD1210 | YAGEO CORPORATION COMPONENT | CC1210MKX5R5BB107 |  | G |  |  |  |  |  |  |  |
|  |  |  |  |  | 18 | 620108J00-026-G |  | CAP,100uF,+/-20%,X5R,6.3V,G,SMD1210 | SAMSUNG SEMICONDUCTOR | CL32A107MQVNNNE |  | G |  |  |  |  |  |  |  |
|  |  |  |  |  | 18 | 620108J07-023-G |  | CAP,100uF,+/-20%,X5R,6.3V,G,SMD1210 | TAIYO ELECTRIC IND.CO.LTD | JMK325ABJ107MM-T |  | G |  |  |  |  |  |  |  |
|  |  |  |  | 19 | 19 | 620100A00-015-G | - | CAP,10uF,+/-10%,X5R,16V,G,SMD1206 | MURATA ELEC. NORTH AMERICA | GRM31CR61C106K | 8 | G | C409,C410,C412,C414,C966,C967,C969,C971 |  |  |  |  |  |  |
|  |  |  |  |  | 19 | 620100A00-026-G |  | CAP,10uF,+/-10%,X5R,16V,G,SMD1206 | SAMSUNG SEMICONDUCTOR | CL31A106KOHNNNE |  | G |  |  |  |  |  |  |  |
|  |  |  |  |  | 19 | 620100A03-023-G |  | CAP,10uF,+/-10%,X5R,16V,G,SMD1206 | TAIYO ELECTRIC IND.CO.LTD | EMK316BJ106KL-T |  | G |  |  |  |  |  |  |  |
|  |  |  |  |  | 19 | 620100A00-012-G |  | CAP,10uF,+/-10%,X5R,16V,G,SMD1206 | WALSIN TECHNOLOGY CORPORATION | 1206X106K160CT |  | G |  |  |  |  |  |  |  |
|  |  |  |  |  | 19 | 620100A00-011-G |  | CAP,10uF,+/-10%,X5R,16V,G,SMD1206 | YAGEO CORPORATION COMPONENT | CC1206KKX5R7BB106 |  | G |  |  |  |  |  |  |  |
|  |  |  |  | 20 | 20 | 62011DF01-015-G | - | CAP,220nF,+/-10%,X7R,16V,G,SMD0402 | MURATA ELEC. NORTH AMERICA | GRM155R71C224K | 288 | G | C416,C417,C418,C419,C420,C421,C422,C423,C424,C425,C426,C427,C428,C429,C430,C431,C432,C433,C434,C435,C436,C437,C438,C439,C440,C441,C442,C443,C444,C445,C446,C447,C448,C449,C450,C451,C452,C453,C454,C455,C456,C457,C458,C459,C460,C461,C462,C463,C464,C465,C466,C467,C468,C469,C470,C471,C472,C473,C474,C475,C476,C477,C478,C479,C480,C481,C482,C485,C488,C489,C490,C491,C496,C497,C498,C499,C504,C505,C506,C507,C512,C513,C514,C515,C516,C517,C518,C519,C520,C521,C522,C523,C524,C525,C526,C527,C528,C529,C530,C531,C532,C533,C534,C535,C536,C537,C538,C539,C540,C541,C542,C543,C544,C545,C550,C551,C552,C553,C554,C555,C560,C561,C562,C563,C568,C569,C570,C571,C576,C577,C578,C582,C584,C585,C586,C587,C592,C593,C594,C595,C600,C601,C602,C603,C822,C823,C824,C825,C826,C827,C828,C829,C830,C831,C832,C833,C834,C835,C836,C837,C838,C839,C840,C841,C842,C843,C844,C845,C846,C847,C848,C849,C850,C851,C852,C853,C854,C855,C856,C857,C858,C859,C860,C862,C863,C864,C865,C866,C867,C868,C869,C870,C871,C872,C873,C874,C875,C876,C877,C878,C879,C880,C881,C882,C883,C884,C885,C886,C887,C888,C889,C890,C891,C892,C893,C894,C895,C896,C897,C898,C899,C900,C901,C910,C911,C912,C913,C914,C915,C916,C917,C918,C919,C920,C921,C922,C923,C924,C925,C926,C927,C928,C929,C930,C931,C932,C933,C934,C935,C936,C937,C938,C939,C940,C941,C942,C943,C944,C945,C946,C947,C948,C949,C950,C951,C952,C953,C954,C955,C956,C957,C958,C959,C960,C961,C962,C963,C964,C965,C2115,C2136,C2138,C2141,C2142,C2144,C2145,C2146,C2166 |  |  |  |  |  |  |
|  |  |  |  |  | 20 | 62011DF00-026-G |  | CAP,220nF,+/-10%,X7R,16V,G,SMD0402 | SAMSUNG SEMICONDUCTOR | CL05B224KO5NNNC |  | G |  |  |  |  |  |  |  |
|  |  |  |  |  | 20 | 62011DF00-023-G |  | CAP,220nF,+/-10%,X7R,16V,G,SMD0402 | TAIYO ELECTRIC IND.CO.LTD | EMK105B7224KV-FR |  | G |  |  |  |  |  |  |  |
|  |  |  |  | 21 | 21 | 620119R04-015-G | - | CAP,22uF,+/-20%,X6S,4V,G,SMD0805 | MURATA ELEC. NORTH AMERICA | GRM21BC80G226M | 35 | G | PSLC7,PSGC7,PSLC8,PSGC8,PSLC11,PSGC11,PSLC12,PSGC12,PFCC14,PSLC15,PSGC15,PFCC15,PFCC16,PFCC17,PFCC18,PFCC20,PFCC21,PFCC22,PFCC23,PFCC24,PFCC25,PFCC26,PFCC27,PFCC28,PFCC29,PECC29,PFCC30,PECC30,PFCC31,PFCC32,PFCC33,PFCC34,PECC40,PECC41,C609 |  |  |  |  |  |  |
|  |  |  |  |  | 21 | 620119R01-015-G |  | CAP,22uF,+/-20%,X6S,4V,G,SMD0805 | MURATA ELEC. NORTH AMERICA | GRM21BC80G226ME39K |  | G |  |  |  |  |  |  |  |
|  |  |  |  |  | 21 | 620119R00-023-G |  | CAP,22uF,+/-20%,X6S,4V,G,SMD0805 | TAIYO ELECTRIC IND.CO.LTD | AMK212C6226MG-T |  | G |  |  |  |  |  |  |  |
|  |  |  |  |  | 21 | 620119R00-026-G |  | CAP,22uF,+/-20%,X6S,4V,G,SMD0805 | SAMSUNG SEMICONDUCTOR | CL21X226MRQNNNE |  | G |  |  |  |  |  |  |  |
|  |  |  |  | 22 | 22 | 62012C800-015-G | - | CAP,100nF,+/-10%,X5R,16V,G,SMD0201 | MURATA ELEC. NORTH AMERICA | GRM033R61C104K | 82 | G | C614,C615,C616,C617,C618,C619,C620,C621,C622,C623,C624,C625,C626,C627,C628,C629,C630,C631,C632,C633,C634,C635,C636,C637,C638,C639,C666,C667,C668,C669,C670,C671,C672,C673,C691,C692,C693,C694,C695,C696,C697,C698,C699,C700,C701,C702,C703,C704,C705,C706,C707,C708,C709,C710,C711,C712,C713,C714,C715,C716,C717,C718,C719,C720,C721,C722,C723,C724,C768,C769,C770,C771,C772,C773,C774,C790,C791,C792,C793,C794,C795,C796 |  |  |  |  |  |  |
|  |  |  |  |  | 22 | 62012C800-023-G |  | CAP,100nF,+/-10%,X5R,16V,G,SMD0201 | TAIYO ELECTRIC IND.CO.LTD | EMK063BJ104KP-F |  | G |  |  |  |  |  |  |  |
|  |  |  |  |  | 22 | 62012C800-026-G |  | CAP,100nF,+/-10%,X5R,16V,G,SMD0201 | SAMSUNG SEMICONDUCTOR | CL03A104KO3NNNC |  | G |  |  |  |  |  |  |  |
|  |  |  |  |  | 22 | 62012C800-011-G |  | CAP,100nF,+/-10%,X5R,16V,G,SMD0201 | YAGEO CORPORATION COMPONENT | CC0201KRX5R7BB104 |  | G |  |  |  |  |  |  |  |
|  |  |  |  | 23 | 23 | 620105400-015-G |  | CAP,1uF,+/-10%,X7R,16V,G,SMD0603 | MURATA ELEC. NORTH AMERICA | GRM188R71C105K | 25 | G | PFCC12,C683,C684,C685,C686,C687,C688,C689,C690,C760,C761,C762,C763,C764,C765,C766,C767,C782,C783,C784,C785,C786,C787,C788,C789 |  |  |  |  |  |  |
|  |  |  |  |  | 23 | 620105400-012-G |  | CAP,1uF,+/-10%,X7R,16V,G,SMD0603 | WALSIN TECHNOLOGY CORPORATION | 0603B105K160CT |  | G |  |  |  |  |  |  |  |
|  |  |  |  |  | 23 | 620105400-011-G |  | CAP,1uF,+/-10%,X7R,16V,G,SMD0603 | YAGEO CORPORATION COMPONENT | CC0603KRX7R7BB105 |  | G |  |  |  |  |  |  |  |
|  |  |  |  |  | 23 | 620105400-026-G |  | CAP,1uF,+/-10%,X7R,16V,G,SMD0603 | SAMSUNG SEMICONDUCTOR | CL10B105KO8NNNC |  | G |  |  |  |  |  |  |  |
|  |  |  |  |  | 23 | 620105400-023-G |  | CAP,1uF,+/-10%,X7R,16V,G,SMD0603 | TAIYO ELECTRIC IND.CO.LTD | EMK107B7105KA-T |  | G |  |  |  |  |  |  |  |
|  |  |  |  | 24 | 24 | 620100L00-015-G | - | CAP,22pF,+/-5%,NPO(C0G),50V,G,SMD0402 | MURATA ELEC. NORTH AMERICA | GRM1555C1H220J | 2 | G | C806,C807 |  |  |  |  |  |  |
|  |  |  |  |  | 24 | 620100L08-012-G |  | CAP,22pF,+/-5%,NPO(C0G),50V,G,SMD0402 | WALSIN TECHNOLOGY CORPORATION | 0402N220J500CT |  | G |  |  |  |  |  |  |  |
|  |  |  |  |  | 24 | 620100L00-023-G |  | CAP,22pF,+/-5%,NPO(C0G),50V,G,SMD0402 | TAIYO ELECTRIC IND.CO.LTD | UMK105CG220JV-F |  | G |  |  |  |  |  |  |  |
|  |  |  |  |  | 24 | 620100L00-026-G |  | CAP,22pF,+/-5%,NPO(C0G),50V,G,SMD0402 | SAMSUNG SEMICONDUCTOR | CL05C220JB5NNNC |  | G |  |  |  |  |  |  |  |
|  |  |  |  | 25 | 25 | 620102U00-015-G | - | CAP,100nF,+/-10%,X5R,10V,G,SMD0402 | MURATA ELEC. NORTH AMERICA | GRM155R61A104K | 3 | G | C808,C2171,C2173 |  |  |  |  |  |  |
|  |  |  |  |  | 25 | 620102U00-023-G |  | CAP,100nF,+/-10%,X5R,10V,G,SMD0402 | TAIYO ELECTRIC IND.CO.LTD | LMK105BJ104KV-F |  | G |  |  |  |  |  |  |  |
|  |  |  |  |  | 25 | 620102U00-011-G |  | CAP,100nF,+/-10%,X5R,10V,G,SMD0402 | YAGEO CORPORATION COMPONENT | CC0402KRX5R6BB104 |  | G |  |  |  |  |  |  |  |
|  |  |  |  |  | 25 | 620102U00-026-G |  | CAP,100nF,+/-10%,X5R,10V,G,SMD0402 | SAMSUNG SEMICONDUCTOR | CL05A104KP5NNNC |  | G |  |  |  |  |  |  |  |
|  |  |  |  |  | 25 | 620102U00-012-G |  | CAP,100nF,+/-10%,X5R,10V,G,SMD0402 | WALSIN TECHNOLOGY CORPORATION | 0402X104K100CT |  | G |  |  |  |  |  |  |  |
|  |  |  |  | 26 | 26 | 62011CA01-015-G |  | CAP,10uF,+/-10%,X5R,10V,G,SMD0603 | MURATA ELEC. NORTH AMERICA | GRM188R61A106K | 1 | G | C2170 |  |  |  |  |  |  |
|  |  |  |  |  | 26 | 62011CA00-026-G |  | CAP,10uF,+/-10%,X5R,10V,G,SMD0603 | SAMSUNG SEMICONDUCTOR | CL10A106KP8NNNC |  | G |  |  |  |  |  |  |  |
|  |  |  |  |  | 26 | 62011CA00-011-G |  | CAP,10uF,+/-10%,X5R,10V,G,SMD0603 | YAGEO CORPORATION COMPONENT | CC0603KRX5R6BB106 |  | G |  |  |  |  |  |  |  |
|  |  |  |  |  | 26 | 62011CA00-012-G |  | CAP,10uF,+/-10%,X5R,10V,G,SMD0603 | WALSIN TECHNOLOGY CORPORATION | 0603X106K100CT |  | G |  |  |  |  |  |  |  |
|  |  |  |  | 27 | 27 | 62010JJ00-015-G | - | CAP,1uF,+/-10%,X5R,10V,G,SMD0402 | MURATA ELEC. NORTH AMERICA | GRM155R61A105K | 2 | G | PECC8,C2172 |  |  |  |  |  |  |
|  |  |  |  |  | 27 | 62010JJ01-023-G |  | CAP,1uF,+/-10%,X5R,10V,G,SMD0402 | TAIYO ELECTRIC IND.CO.LTD | LMK105BJ105KV-F |  | G |  |  |  |  |  |  |  |
|  |  |  |  |  | 27 | 62010JJ00-011-G |  | CAP,1uF,+/-10%,X5R,10V,G,SMD0402 | YAGEO CORPORATION COMPONENT | CC0402KRX5R6BB105 |  | G |  |  |  |  |  |  |  |
|  |  |  |  |  | 27 | 62010JJ00-012-G |  | CAP,1uF,+/-10%,X5R,10V,G,SMD0402 | WALSIN TECHNOLOGY CORPORATION | 0402X105K100CT |  | G |  |  |  |  |  |  |  |
|  |  |  |  |  | 27 | 62010JJ00-026-G |  | CAP,1uF,+/-10%,X5R,10V,G,SMD0402 | SAMSUNG SEMICONDUCTOR | CL05A105KP5NNNC |  | G |  |  |  |  |  |  |  |
|  |  |  |  | 28 | 28 | 520308900-214-G | - | DIODE,Schottky,BAR43FILM,30V,0.1A,G,SOT23-3,SMD | ST MICRO ELECTRONICS,INC | BAR43FILM | 7 | G | D1,D2,D3,D4,D5,D6,D7 |  |  |  |  |  |  |
|  |  |  |  | 29 | 29 | 521107T00-289-G | KX549 | LED,Gre,LTST-C190KGKT,2.4V,30mA,G,SMD0603 | LITE-ON TECHNOLOGY CORPORATION | LTST-C190KGKT | 29 | G | LED_HB1,LED_BLK1,LED_SASEXP_P0V9,LED_SW1_P0,LED_SW1_P1,LED_SW1_P2,LED_SW1_P3,LED_SW1_P4,LED_SW1_P5,LED_SW1_P6,LED_SW1_P7,LED_SW1_P8,LED_SW1_P9,LED_SW1_P10,LED_SW1_P11,LED_SW1_P12,LED_SW1_P13,LED_SW1_P14,LED_SW1_P15,LED_SW1_P16,LED_SW1_P17,LED_SW1_P18,LED_SW1_P19,LED_SW1_P20,LED_SW1_P21,LED_SW1_P22,LED_SW1_P23,LED_PEX9797_PG,LED_EXP_BP_PG |  |  |  |  |  |  |
|  |  |  |  | 30 | 30 | 72010KB01-016-G | - | FB,330 Ohm@100MHz,+/-25%,2.5A,50mOhm,G,SMD0805 | TDK ELECTRONICS EUROPE GMBH | MPZ2012S331AT | 1 | G | L1 |  |  |  |  |  |  |
|  |  |  |  | 31 | 31 | 720103500-059-G |  | FB,600 Ohm@100MHz,+/-25%,2A,100mOhm,G,SMD0805 | TAI-TECH Advanced Electronics Co., Ltd. | HCB2012KF-601T20 | 10 | G | L2,L3,L4,L5,L6,L7,L8,L9,L10,L11 |  |  |  |  |  |  |
|  |  |  |  | 32 | 32 | 720105N00-016-G | - | FB,30 Ohm@100MHz,+/-33%,5A,10mOhm,G,SMD0805 | TDK ELECTRONICS EUROPE GMBH | MPZ2012S300AT | 12 | G | L12,L13,L14,L15,L16,L17,L18,L19,L20,L21,L22,L23 |  |  |  |  |  |  |
|  |  |  |  | 33 | 33 | 720105E04-016-G |  | FB,600Ohm@100MHz,+/-25%,500mA,400mOhm,SMD0603,G | TDK ELECTRONICS EUROPE GMBH | MMZ1608B601CTAH0 | 1 | G | L24 |  |  |  |  |  |  |
|  |  |  |  | 34 | 34 | 62120D701-021-G |  | SPEA CAP,180uF,+/-20%,16V,105C,G,SMD6.3*5.8,ESR<=22mOhm | NIPPON CHEMI-CON CORPORATION | APXG160ARA181MF61G | 1 | G | PECCE1 |  |  |  |  |  |  |
|  |  |  |  | 35 | 35 | 62120ES00-024-G | - | SPEA CAP,560uF,+/-20%,2V,105C,G,SMD2816,ESR<=3mOhm | PANASONIC INDUSTRIAL CO.,LTD. | EEFGX0D561L | 4 | G | PECCE3,PECCE4,PECCE5,PECCE6 |  |  |  |  |  |  |
|  |  |  |  | 36 | 36 | 620103K00-015-G | - | CAP,1nF,+/-10%,X7R,50V,G,SMD0402 | MURATA ELEC. NORTH AMERICA | GRM155R71H102K | 3 | G | PECC1,PELC17,PFCC19 |  |  |  |  |  |  |
|  |  |  |  |  | 36 | 620103K00-012-G |  | CAP,1nF,+/-10%,X7R,50V,G,SMD0402 | WALSIN TECHNOLOGY CORPORATION | 0402B102K500CT |  | G |  |  |  |  |  |  |  |
|  |  |  |  |  | 36 | 620103K00-026-G |  | CAP,1nF,+/-10%,X7R,50V,G,SMD0402 | SAMSUNG SEMICONDUCTOR | CL05B102KB5NNNC |  | G |  |  |  |  |  |  |  |
|  |  |  |  |  | 36 | 620103K00-023-G |  | CAP,1nF,+/-10%,X7R,50V,G,SMD0402 | TAIYO ELECTRIC IND.CO.LTD | UMK105B7102KV-F |  | G |  |  |  |  |  |  |  |
|  |  |  |  | 37 | 37 | 62010FY00-015-G | - | CAP,1.5nF,+/-10%,X7R,50V,G,SMD0402 | MURATA ELEC. NORTH AMERICA | GRM155R71H152K | 1 | G | PECC2 |  |  |  |  |  |  |
|  |  |  |  |  | 37 | 62010FY00-012-G |  | CAP,1.5nF,+/-10%,X7R,50V,G,SMD0402 | WALSIN TECHNOLOGY CORPORATION | 0402B152K500CT |  | G |  |  |  |  |  |  |  |
|  |  |  |  |  | 37 | 62010FY00-026-G |  | CAP,1.5nF,+/-10%,X7R,50V,G,SMD0402 | SAMSUNG SEMICONDUCTOR | CL05B152KB5NNNC |  | G |  |  |  |  |  |  |  |
|  |  |  |  |  | 37 | 62010FY00-023-G |  | CAP,1.5nF,+/-10%,X7R,50V,G,SMD0402 | TAIYO ELECTRIC IND.CO.LTD | UMK105B7152KV-F |  | G |  |  |  |  |  |  |  |
|  |  |  |  | 38 | 38 | 620103U00-015-G | - | CAP,470pF,+/-10%,X7R,50V,G,SMD0402 | MURATA ELEC. NORTH AMERICA | GRM155R71H471K | 1 | G | PECC4 |  |  |  |  |  |  |
|  |  |  |  |  | 38 | 620103U00-012-G |  | CAP,470pF,+/-10%,X7R,50V,G,SMD0402 | WALSIN TECHNOLOGY CORPORATION | 0402B471K500CT |  | G |  |  |  |  |  |  |  |
|  |  |  |  |  | 38 | 620103U00-026-G |  | CAP,470pF,+/-10%,X7R,50V,G,SMD0402 | SAMSUNG SEMICONDUCTOR | CL05B471KB5NNNC |  | G |  |  |  |  |  |  |  |
|  |  |  |  |  | 38 | 620103U00-023-G |  | CAP,470pF,+/-10%,X7R,50V,G,SMD0402 | TAIYO ELECTRIC IND.CO.LTD | UMK105B7471KV-F |  | G |  |  |  |  |  |  |  |
|  |  |  |  | 39 | 39 | 620114T00-015-G | - | CAP,330nF,+/-10%,X5R,10V,G,SMD0402 | MURATA ELEC. NORTH AMERICA | GRM155R61A334K | 1 | G | PECC7 |  |  |  |  |  |  |
|  |  |  |  |  | 39 | 620114T00-012-G |  | CAP,330nF,+/-10%,X5R,10V,G,SMD0402 | WALSIN TECHNOLOGY CORPORATION | 0402X334K100CT |  | G |  |  |  |  |  |  |  |
|  |  |  |  |  | 39 | 620114T00-011-G |  | CAP,330nF,+/-10%,X5R,10V,G,SMD0402 | YAGEO CORPORATION COMPONENT | CC0402KRX5R6BB334 |  | G |  |  |  |  |  |  |  |
|  |  |  |  | 40 | 40 | 62012GE00-015-G | - | CAP,4.7uF,+/-20%,X7S,10V,G,SMD0603 | MURATA ELEC. NORTH AMERICA | GRM188C71A475M | 1 | G | PECC9 |  |  |  |  |  |  |
|  |  |  |  |  | 40 | 62012T800-023-G |  | CAP,4.7uF,+/-10%,X7S,10V,G,SMD0603 | TAIYO ELECTRIC IND.CO.LTD | LDK107BC7475KA-T |  | G |  |  |  |  |  |  |  |
|  |  |  |  | 41 | 41 | 62011F100-015-G |  | CAP,1uF,+/-10%,X7R,25V,G,SMD0603 | MURATA ELEC. NORTH AMERICA | GRM188R71E105K | 2 | G | PFCC3,PECC10 |  |  |  |  |  |  |
|  |  |  |  |  | 41 | 62011F100-023-G |  | CAP,1uF,+/-10%,X7R,25V,G,SMD0603 | TAIYO ELECTRIC IND.CO.LTD | TMK107B7105KA-T |  | G |  |  |  |  |  |  |  |
|  |  |  |  |  | 41 | 62011F100-026-G |  | CAP,1uF,+/-10%,X7R,25V,G,SMD0603 | SAMSUNG SEMICONDUCTOR | CL10B105KA8NNNC |  | G |  |  |  |  |  |  |  |
|  |  |  |  | 42 | 42 | 62010L800-015-G | - | CAP,1nF,+/-5%,NPO(C0G),50V,G,SMD0402 | MURATA ELEC. NORTH AMERICA | GRM1555C1H102J | 3 | G | PSCC5,PECC11,PECC12 |  |  |  |  |  |  |
|  |  |  |  |  | 42 | 62010L800-012-G |  | CAP,1nF,+/-5%,NPO(C0G),50V,G,SMD0402 | WALSIN TECHNOLOGY CORPORATION | 0402N102J500CT |  | G |  |  |  |  |  |  |  |
|  |  |  |  |  | 42 | 62010L800-026-G |  | CAP,1nF,+/-5%,NPO(C0G),50V,G,SMD0402 | SAMSUNG SEMICONDUCTOR | CL05C102JB5NNNC |  | G |  |  |  |  |  |  |  |
|  |  |  |  | 43 | 43 | 62012P100-015-G |  | CAP,2.2uF,+/-20%,X7S,10V,G,SMD0402 | MURATA ELEC. NORTH AMERICA | GRM155C71A225M | 5 | G | PSRC5,PSLC5,PSGC5,PECC14,PECC17 |  |  |  |  |  |  |
|  |  |  |  |  | 43 | 62012P100-012-G |  | CAP,2.2uF,+/-20%,X7S,10V,G,SMD0402 | WALSIN TECHNOLOGY CORPORATION | 0402A225M100CT |  | G |  |  |  |  |  |  |  |
|  |  |  |  | 44 | 44 | 620109700-015-G |  | CAP,3.3nF,+/-10%,X7R,50V,G,SMD0402 | MURATA ELEC. NORTH AMERICA | GRM155R71H332K | 7 | G | PLTC6,PECC20,PECC21,PECC22,PECC31,PECC32,PECC33 |  |  |  |  |  |  |
|  |  |  |  |  | 44 | 620109700-012-G |  | CAP,3.3nF,+/-10%,X7R,50V,G,SMD0402 | WALSIN TECHNOLOGY CORPORATION | 0402B332K500CT |  | G |  |  |  |  |  |  |  |
|  |  |  |  |  | 44 | 620109700-026-G |  | CAP,3.3nF,+/-10%,X7R,50V,G,SMD0402 | SAMSUNG SEMICONDUCTOR | CL05B332KB5NNNC |  | G |  |  |  |  |  |  |  |
|  |  |  |  | 45 | 45 | 62011HS01-015-G |  | CAP,10uF,+/-10%,X7R,25V,G,SMD1206 | MURATA ELEC. NORTH AMERICA | GRM31CR71E106K | 21 | G | PFCC5,PELC5,PFCC6,PELC6,PFCC7,PELC7,PFCC8,PELC8,PFCC9,PECC23,PECC24,PECC25,PECC26,PECC27,PECC28,PECC34,PECC35,PECC36,PECC37,PECC38,PECC39 |  |  |  |  |  |  |
|  |  |  |  |  | 45 | 62011HS00-026-G |  | CAP,10uF,+/-10%,X7R,25V,G,SMD1206 | SAMSUNG SEMICONDUCTOR | CL31B106KAHNNNE |  | G |  |  |  |  |  |  |  |
|  |  |  |  |  | 45 | 62011HS00-023-G |  | CAP,10uF,+/-10%,X7R,25V,G,SMD1206 | TAIYO ELECTRIC IND.CO.LTD | TMK316B7106KL-TD |  | G |  |  |  |  |  |  |  |
|  |  |  |  | 46 | 46 | 620113A01-015-G | - | CAP,680pF,+/-5%,NPO,50V,G,SMD0402 | MURATA ELEC. NORTH AMERICA | GRM1555C1H681J | 2 | G | PECC42,PECC43 |  |  |  |  |  |  |
|  |  |  |  |  | 46 | 620113A00-012-G |  | CAP,680pF,+/-5%,NPO(C0G),50V,G,SMD0402 | WALSIN TECHNOLOGY CORPORATION | 0402N681J500LT |  | G |  |  |  |  |  |  |  |
|  |  |  |  |  | 46 | 620113A00-025-G |  | CAP,680pF,+/-5%,NPO(C0G),50V,G,SMD0402 | KEMET ELECTRONICS CORPORATION | C0402C681J5GAC |  | G |  |  |  |  |  |  |  |
|  |  |  |  |  | 46 | 620113A00-016-G |  | CAP,680pF,+/-5%,NPO(C0G),50V,G,SMD0402 | TDK ELECTRONICS EUROPE GMBH | C1005C0G1H681JT |  | G |  |  |  |  |  |  |  |
|  |  |  |  | 47 | 47 | 62012G200-015-G | - | CAP,22uF,+/-20%,X6S,4V,G,SMD0603 | MURATA ELEC. NORTH AMERICA | GRM188C80G226M | 12 | G | PECC44,PECC45,PECC46,PECC47,PECC48,PECC49,PECC50,PECC51,PECC52,PECC53,PECC54,PECC55 |  |  |  |  |  |  |
|  |  |  |  |  | 47 | 62012G200-012-G |  | CAP,22uF,+/-20%,X6S,4V,G,SMD0603 | WALSIN TECHNOLOGY CORPORATION | 0603S226M4R0CT |  | G |  |  |  |  |  |  |  |
|  |  |  |  |  | 47 | 62012G200-026-G |  | CAP,22uF,+/-20%,X6S,4V,G,SMD0603 | SAMSUNG SEMICONDUCTOR | CL10X226MR8NUNE |  | G |  |  |  |  |  |  |  |
|  |  |  |  |  | 47 | 62012G200-023-G |  | CAP,22uF,+/-20%,X6S,4V,G,SMD0603 | TAIYO ELECTRIC IND.CO.LTD | AMK107BC6226MA-T |  | G |  |  |  |  |  |  |  |
|  |  |  |  | 48 | 48 | 630330400-088-G | - | IND,150nH@100KHz,+/-10%,51A,304.5uOhm,SHLD,G,SMD | COOPER BUSSMANN, INC. | FP0906R1-R15-R | 2 | G | PECL1,PECL2 |  |  |  |  |  |  |
|  |  |  |  | 49 | 49 | 63035Y500-129-G |  | IND,22nH@100KHz,+/-15%,22A,249.55uOhm,SHLD,G,SMD | MAG.LAYERS, SCIENTIFIC-TECHNICS (KUNSHAN) CO., LTD. | MSI-400404-22NL-I | 1 | G | PECL3 |  |  |  |  |  |  |
|  |  |  |  | 50 | 50 | 61100LQ00-017-G |  | RES,20KOhm,+/-1%,1/16W,G,SMD0402 | KOA SPEER ELECTRONICS, INC. | RN731ETTP2002F50 | 1 | G | PECR1 |  |  |  |  |  |  |
|  |  |  |  |  | 50 | 61100LQ00-011-G |  | RES,20KOhm,+/-1%,1/16W,G,SMD0402 | YAGEO CORPORATION COMPONENT | RT0402FRE0720KL |  | G |  |  |  |  |  |  |  |
|  |  |  |  |  | 50 | 61100LQ00-044-G |  | RES,20KOhm,+/-1%,1/16W,G,SMD0402 | TA-I TECHNOLOGY CO., LTD. | RB04FTS2002 |  | G |  |  |  |  |  |  |  |
|  |  |  |  |  | 50 | 61100LQ00-012-G |  | RES,20KOhm,+/-1%,1/16W,G,SMD0402 | WALSIN TECHNOLOGY CORPORATION | WF04T2002FTL |  | G |  |  |  |  |  |  |  |
|  |  |  |  | 51 | 51 | 61011FP00-017-G |  | RES,113KOhm,+/-1%,1/16W,G,SMD0402 | KOA SPEER ELECTRONICS, INC. | RK73H1ETTP1133F | 2 | G | PECR2,PECR13 |  |  |  |  |  |  |
|  |  |  |  |  | 51 | 61011FP00-011-G |  | RES,113KOhm,+/-1%,1/16W,G,SMD0402 | YAGEO CORPORATION COMPONENT | RC0402FR-07113KL |  | G |  |  |  |  |  |  |  |
|  |  |  |  |  | 51 | 61011FP00-012-G |  | RES,113KOhm,+/-1%,1/16W,G,SMD0402 | WALSIN TECHNOLOGY CORPORATION | WR04X1133FTL |  | G |  |  |  |  |  |  |  |
|  |  |  |  |  | 51 | 61011FP00-044-G |  | RES,113KOhm,+/-1%,1/16W,G,SMD0402 | TA-I TECHNOLOGY CO., LTD. | RM04FTN1133 |  | G |  |  |  |  |  |  |  |
|  |  |  |  | 52 | 52 | 61011HP00-017-G |  | RES,44.2KOhm,+/-1%,1/16W,G,SMD0402 | KOA SPEER ELECTRONICS, INC. | RK73H1ETTP4422F | 1 | G | PECR3 |  |  |  |  |  |  |
|  |  |  |  |  | 52 | 61011HP00-012-G |  | RES,44.2KOhm,+/-1%,1/16W,G,SMD0402 | WALSIN TECHNOLOGY CORPORATION | WR04X4422FTL |  | G |  |  |  |  |  |  |  |
|  |  |  |  |  | 52 | 61011HP00-011-G |  | RES,44.2KOhm,+/-1%,1/16W,G,SMD0402 | YAGEO CORPORATION COMPONENT | RC0402FR-0744K2L |  | G |  |  |  |  |  |  |  |
|  |  |  |  |  | 52 | 61011HP00-044-G |  | RES,44.2KOhm,+/-1%,1/16W,G,SMD0402 | TA-I TECHNOLOGY CO., LTD. | RM04FTN4422 |  | G |  |  |  |  |  |  |  |
|  |  |  |  | 53 | 53 | 61011LH00-017-G |  | RES,9.31KOhm,+/-1%,1/16W,G,SMD0402 | KOA SPEER ELECTRONICS, INC. | RK73H1ETTP9311F | 1 | G | PECR4 |  |  |  |  |  |  |
|  |  |  |  |  | 53 | 61011LH00-011-G |  | RES,9.31KOhm,+/-1%,1/16W,G,SMD0402 | YAGEO CORPORATION COMPONENT | RC0402FR-079K31L |  | G |  |  |  |  |  |  |  |
|  |  |  |  |  | 53 | 61011LH00-012-G |  | RES,9.31KOhm,+/-1%,1/16W,G,SMD0402 | WALSIN TECHNOLOGY CORPORATION | WR04X9311FTL |  | G |  |  |  |  |  |  |  |
|  |  |  |  |  | 53 | 61011LH00-044-G |  | RES,9.31KOhm,+/-1%,1/16W,G,SMD0402 | TA-I TECHNOLOGY CO., LTD. | RM04FTN9311 |  | G |  |  |  |  |  |  |  |
|  |  |  |  | 54 | 54 | 61011H600-017-G |  | RES,16.5KOhm,+/-1%,1/16W,G,SMD0402 | KOA SPEER ELECTRONICS, INC. | RK73H1ETTP1652F | 1 | G | PECR5 |  |  |  |  |  |  |
|  |  |  |  |  | 54 | 61011H600-011-G |  | RES,16.5KOhm,+/-1%,1/16W,G,SMD0402 | YAGEO CORPORATION COMPONENT | RC0402FR-0716K5L |  | G |  |  |  |  |  |  |  |
|  |  |  |  |  | 54 | 61011H600-012-G |  | RES,16.5KOhm,+/-1%,1/16W,G,SMD0402 | WALSIN TECHNOLOGY CORPORATION | WR04X1652FTL |  | G |  |  |  |  |  |  |  |
|  |  |  |  | 55 | 55 | 610127Q00-017-G |  | RES,357KOhm,+/-1%,1/16W,G,SMD0402 | KOA SPEER ELECTRONICS, INC. | RK73H1ETTP3573F | 1 | G | PECR6 |  |  |  |  |  |  |
|  |  |  |  |  | 55 | 610127Q00-012-G |  | RES,357KOhm,+/-1%,1/16W,G,SMD0402 | WALSIN TECHNOLOGY CORPORATION | WR04X3573FTL |  | G |  |  |  |  |  |  |  |
|  |  |  |  |  | 55 | 610127Q00-011-G |  | RES,357KOhm,+/-1%,1/16W,G,SMD0402 | YAGEO CORPORATION COMPONENT | RC0402FR-07357KL |  | G |  |  |  |  |  |  |  |
|  |  |  |  |  | 55 | 610127Q00-044-G |  | RES,357KOhm,+/-1%,1/16W,G,SMD0402 | TA-I TECHNOLOGY CO., LTD. | RM04FTN3573 |  | G |  |  |  |  |  |  |  |
|  |  |  |  | 56 | 56 | 61011MG00-017-G |  | RES,42.2KOhm,+/-1%,1/16W,G,SMD0402 | KOA SPEER ELECTRONICS, INC. | RK73H1ETTP4222F | 1 | G | PECR7 |  |  |  |  |  |  |
|  |  |  |  |  | 56 | 61011MG00-012-G |  | RES,42.2KOhm,+/-1%,1/16W,G,SMD0402 | WALSIN TECHNOLOGY CORPORATION | WR04X4222FTL |  | G |  |  |  |  |  |  |  |
|  |  |  |  |  | 56 | 61011MG00-011-G |  | RES,42.2KOhm,+/-1%,1/16W,G,SMD0402 | YAGEO CORPORATION COMPONENT | RC0402FR-0742K2L |  | G |  |  |  |  |  |  |  |
|  |  |  |  |  | 56 | 61011MG00-044-G |  | RES,42.2KOhm,+/-1%,1/16W,G,SMD0402 | TA-I TECHNOLOGY CO., LTD. | RM04FTN4222 |  | G |  |  |  |  |  |  |  |
|  |  |  |  | 57 | 57 | 61011AQ00-017-G |  | RES,30.1KOhm,+/-1%,1/16W,G,SMD0402 | KOA SPEER ELECTRONICS, INC. | RK73H1ETTP3012F | 2 | G | PECR8,PECR12 |  |  |  |  |  |  |
|  |  |  |  |  | 57 | 61011AQ00-012-G |  | RES,30.1KOhm,+/-1%,1/16W,G,SMD0402 | WALSIN TECHNOLOGY CORPORATION | WR04X3012FTL |  | G |  |  |  |  |  |  |  |
|  |  |  |  |  | 57 | 61011AQ00-011-G |  | RES,30.1KOhm,+/-1%,1/16W,G,SMD0402 | YAGEO CORPORATION COMPONENT | RC0402FR-0730K1L |  | G |  |  |  |  |  |  |  |
|  |  |  |  |  | 57 | 61011AQ00-044-G |  | RES,30.1KOhm,+/-1%,1/16W,G,SMD0402 | TA-I TECHNOLOGY CO., LTD. | RM04FTN3012 |  | G |  |  |  |  |  |  |  |
|  |  |  |  | 58 | 58 | 61100K600-011-G |  | RES,24KOhm,+/-0.1%,1/16W,G,SMD0402 | YAGEO CORPORATION COMPONENT | RT0402BRD0724KL | 1 | G | PECR9 |  |  |  |  |  |  |
|  |  |  |  | 59 | 59 | 610116G00-017-G | - | RES,150KOhm,+/-1%,1/16W,G,SMD0402 | KOA SPEER ELECTRONICS, INC. | RK73H1ETTP1503F | 1 | G | PECR10 |  |  |  |  |  |  |
|  |  |  |  |  | 59 | 610116G00-011-G |  | RES,150KOhm,+/-1%,1/16W,G,SMD0402 | YAGEO CORPORATION COMPONENT | RC0402FR-07150KL |  | G |  |  |  |  |  |  |  |
|  |  |  |  |  | 59 | 610116G00-012-G |  | RES,150KOhm,+/-1%,1/16W,G,SMD0402 | WALSIN TECHNOLOGY CORPORATION | WR04X1503FTL |  | G |  |  |  |  |  |  |  |
|  |  |  |  |  | 59 | 610116G00-044-G |  | RES,150KOhm,+/-1%,1/16W,G,SMD0402 | TA-I TECHNOLOGY CO., LTD. | RM04FTN1503 |  | G |  |  |  |  |  |  |  |
|  |  |  |  | 60 | 60 | 610114H00-017-G | - | RES,20KOhm,+/-1%,1/16W,G,SMD0402 | KOA SPEER ELECTRONICS, INC. | RK73H1ETTP2002F | 2 | G | PELR10,PECR11 |  |  |  |  |  |  |
|  |  |  |  |  | 60 | 610114H00-011-G |  | RES,20KOhm,+/-1%,1/16W,G,SMD0402 | YAGEO CORPORATION COMPONENT | RC0402FR-0720KL |  | G |  |  |  |  |  |  |  |
|  |  |  |  |  | 60 | 610114H00-012-G |  | RES,20KOhm,+/-1%,1/16W,G,SMD0402 | WALSIN TECHNOLOGY CORPORATION | WR04X2002FTL |  | G |  |  |  |  |  |  |  |
|  |  |  |  |  | 60 | 610114H00-044-G |  | RES,20KOhm,+/-1%,1/16W,G,SMD0402 | TA-I TECHNOLOGY CO., LTD. | RM04FTN2002 |  | G |  |  |  |  |  |  |  |
|  |  |  |  |  | 60 | 610114H00-024-G |  | RES,20KOhm,+/-1%,1/16W,G,SMD0402 | PANASONIC INDUSTRIAL CO.,LTD. | ERJ2RKF2002x |  | G |  |  |  |  |  |  |  |
|  |  |  |  |  | 60 | 610114H00-030-G |  | RES,20KOhm,+/-1%,1/16W,G,SMD0402 | ROHM CORPORATION | MCR01MZPF2002 |  | G |  |  |  |  |  |  |  |
|  |  |  |  |  | 60 | 610114H04-029-G |  | RES,20KOhm,+/-1%,1/16W,G,SMD0402 | VISHAY ENTER TECHNO LOGY.INC | CRCW040220K0FKEDC |  | G |  |  |  |  |  |  |  |
|  |  |  |  | 61 | 61 | 61011TN00-017-G |  | RES,39KOhm,+/-1%,1/16W,G,SMD0402 | KOA SPEER ELECTRONICS, INC. | RK73H1ETTP3902F | 1 | G | PECR14 |  |  |  |  |  |  |
|  |  |  |  |  | 61 | 61011TN00-011-G |  | RES,39KOhm,+/-1%,1/16W,G,SMD0402 | YAGEO CORPORATION COMPONENT | RC0402FR-0739KL |  | G |  |  |  |  |  |  |  |
|  |  |  |  |  | 61 | 61011TN00-012-G |  | RES,39KOhm,+/-1%,1/16W,G,SMD0402 | WALSIN TECHNOLOGY CORPORATION | WR04X3902FTL |  | G |  |  |  |  |  |  |  |
|  |  |  |  |  | 61 | 61011TN00-044-G |  | RES,39KOhm,+/-1%,1/16W,G,SMD0402 | TA-I TECHNOLOGY CO., LTD. | RM04FTN3902 |  | G |  |  |  |  |  |  |  |
|  |  |  |  | 62 | 62 | 61010L300-017-G | - | RES,1KOhm,+/-1%,1/16W,G,SMD0402 | KOA SPEER ELECTRONICS, INC. | RK73H1ETTP1001F | 24 | G | PECR16,PECR25,R206,R207,R216,R217,R226,R227,R378,R379,R380,R387,R388,R389,R390,R403,R433,R434,R435,R438,R1401,R1402,R1537,R1538 |  |  |  |  |  |  |
|  |  |  |  |  | 62 | 61010L300-012-G |  | RES,1KOhm,+/-1%,1/16W,G,SMD0402 | WALSIN TECHNOLOGY CORPORATION | WR04X1001FTL |  | G |  |  |  |  |  |  |  |
|  |  |  |  |  | 62 | 61010L300-011-G |  | RES,1KOhm,+/-1%,1/16W,G,SMD0402 | YAGEO CORPORATION COMPONENT | RC0402FR-071KL |  | G |  |  |  |  |  |  |  |
|  |  |  |  |  | 62 | 61010L300-044-G |  | RES,1KOhm,+/-1%,1/16W,G,SMD0402 | TA-I TECHNOLOGY CO., LTD. | RM04FTN1001 |  | G |  |  |  |  |  |  |  |
|  |  |  |  |  | 62 | 61010L300-024-G |  | RES,1KOhm,+/-1%,1/16W,G,SMD0402 | PANASONIC INDUSTRIAL CO.,LTD. | ERJ2RKF1001X |  | G |  |  |  |  |  |  |  |
|  |  |  |  |  | 62 | 61010L300-029-G |  | RES,1KOhm,+/-1%,1/16W,G,SMD0402 | VISHAY ENTER TECHNO LOGY.INC | CRCW04021K00FKED |  | G |  |  |  |  |  |  |  |
|  |  |  |  | 63 | 63 | 610107A00-017-G | - | RES,0 Ohm,+/-5%,1/16W,G,SMD0402 | KOA SPEER ELECTRONICS, INC. | RK73Z1ETTP | 79 | G | PLTR1,PSLR2,PSGR2,PSCR2,PFCR2,PELR2,PFCR3,PSCR7,PELR7,PSRR8,PSCR8,PSRR9,PSLR9,PSGR9,PFCR9,PELR9,R11,PFCR11,PSLR13,PSCR14,PSRR15,PSLR15,PSGR15,PELR15,PELR16,PFCR17,PELR17,PSRR18,PSLR18,PSGR18,PFCR18,PSCR22,PECR22,PECR23,PECR28,PECR30,PECR37,PECR38,PECR41,PECR42,PECR44,PECR52,PECR53,R131,R132,R133,R135,R137,R189,R198,R204,R205,R212,R213,R214,R215,R220,R221,R222,R223,R237,R250,R1387,R1388,R1410,R1441,R1445,R1513,R1514,R1515,R1516,R1520,R1524,R1535,R1536,R1540,PSCR3001,PSCR3002,PSCR3003 |  |  |  |  |  |  |
|  |  |  |  |  | 63 | 610107A00-012-G |  | RES,0 Ohm,+/-5%,1/16W,G,SMD0402 | WALSIN TECHNOLOGY CORPORATION | WR04X000PTL |  | G |  |  |  |  |  |  |  |
|  |  |  |  |  | 63 | 610107A00-011-G |  | RES,0 Ohm,+/-5%,1/16W,G,SMD0402 | YAGEO CORPORATION COMPONENT | RC0402JR-070RL |  | G |  |  |  |  |  |  |  |
|  |  |  |  |  | 63 | 610107A00-044-G |  | RES,0 Ohm,+/-5%,1/16W,G,SMD0402 | TA-I TECHNOLOGY CO., LTD. | RM04JTN0 |  | G |  |  |  |  |  |  |  |
|  |  |  |  |  | 63 | 610107A00-024-G |  | RES,0 Ohm,+/-5%,1/16W,G,SMD0402 | PANASONIC INDUSTRIAL CO.,LTD. | ERJ2GE0R00X |  | G |  |  |  |  |  |  |  |
|  |  |  |  |  | 63 | 610107A00-029-G |  | RES,0 Ohm,+/-5%,1/16W,G,SMD0402 | VISHAY ENTER TECHNO LOGY.INC | CRCW04020000Z0ED |  | G |  |  |  |  |  |  |  |
|  |  |  |  | 64 | 64 | 61010LE00-017-G |  | RES,12KOhm,+/-1%,1/16W,G,SMD0402 | KOA SPEER ELECTRONICS, INC. | RK73H1ETTP1202F | 1 | G | PECR24 |  |  |  |  |  |  |
|  |  |  |  |  | 64 | 61010LE00-011-G |  | RES,12KOhm,+/-1%,1/16W,G,SMD0402 | YAGEO CORPORATION COMPONENT | RC0402FR-0712KL |  | G |  |  |  |  |  |  |  |
|  |  |  |  |  | 64 | 61010LE00-012-G |  | RES,12KOhm,+/-1%,1/16W,G,SMD0402 | WALSIN TECHNOLOGY CORPORATION | WR04X1202FTL |  | G |  |  |  |  |  |  |  |
|  |  |  |  |  | 64 | 61010LE00-044-G |  | RES,12KOhm,+/-1%,1/16W,G,SMD0402 | TA-I TECHNOLOGY CO., LTD. | RM04FTN1202 |  | G |  |  |  |  |  |  |  |
|  |  |  |  | 65 | 65 | 610114S00-017-G | - | RES,4.99KOhm,+/-1%,1/16W,G,SMD0402 | KOA SPEER ELECTRONICS, INC. | RK73H1ETTP4991F | 3 | G | PSRR3,PSCR9,PECR26 |  |  |  |  |  |  |
|  |  |  |  |  | 65 | 610114S00-012-G |  | RES,4.99KOhm,+/-1%,1/16W,G,SMD0402 | WALSIN TECHNOLOGY CORPORATION | WR04X4991FTL |  | G |  |  |  |  |  |  |  |
|  |  |  |  |  | 65 | 610114S00-011-G |  | RES,4.99KOhm,+/-1%,1/16W,G,SMD0402 | YAGEO CORPORATION COMPONENT | RC0402FR-074K99L |  | G |  |  |  |  |  |  |  |
|  |  |  |  |  | 65 | 610114S00-044-G |  | RES,4.99KOhm,+/-1%,1/16W,G,SMD0402 | TA-I TECHNOLOGY CO., LTD. | RM04FTN4991 |  | G |  |  |  |  |  |  |  |
|  |  |  |  |  | 65 | 610114S00-024-G |  | RES,4.99KOhm,+/-1%,1/16W,G,SMD0402 | PANASONIC INDUSTRIAL CO.,LTD. | ERJ2RKF4991X |  | G |  |  |  |  |  |  |  |
|  |  |  |  | 66 | 66 | 61011GY00-017-G | - | RES,2.43KOhm,+/-1%,1/16W,G,SMD0402 | KOA SPEER ELECTRONICS, INC. | RK73H1ETTP2431F | 1 | G | PECR27 |  |  |  |  |  |  |
|  |  |  |  |  | 66 | 61011GY00-012-G |  | RES,2.43KOhm,+/-1%,1/16W,G,SMD0402 | WALSIN TECHNOLOGY CORPORATION | WR04X2431FTL |  | G |  |  |  |  |  |  |  |
|  |  |  |  |  | 66 | 61011GY00-011-G |  | RES,2.43KOhm,+/-1%,1/16W,G,SMD0402 | YAGEO CORPORATION COMPONENT | RC0402FR-072K43L |  | G |  |  |  |  |  |  |  |
|  |  |  |  |  | 66 | 61011GY00-044-G |  | RES,2.43KOhm,+/-1%,1/16W,G,SMD0402 | TA-I TECHNOLOGY CO., LTD. | RM04FTN2431 |  | G |  |  |  |  |  |  |  |
|  |  |  |  | 67 | 67 | 61011C300-017-G |  | RES,2.2 Ohm,+/-1%,1/16W,G,SMD0402 | KOA SPEER ELECTRONICS, INC. | RK73H1ETTP2R20F | 1 | G | PECR29 |  |  |  |  |  |  |
|  |  |  |  |  | 67 | 61011C300-012-G |  | RES,2.2 Ohm,+/-1%,1/16W,G,SMD0402 | WALSIN TECHNOLOGY CORPORATION | WR04W2R20FTL |  | G |  |  |  |  |  |  |  |
|  |  |  |  |  | 67 | 61011C300-011-G |  | RES,2.2 Ohm,+/-1%,1/16W,G,SMD0402 | YAGEO CORPORATION COMPONENT | RC0402FR-072R2L |  | G |  |  |  |  |  |  |  |
|  |  |  |  |  | 67 | 61011C300-044-G |  | RES,2.2 Ohm,+/-1%,1/16W,G,SMD0402 | TA-I TECHNOLOGY CO., LTD. | RM04FTN2R20 |  | G |  |  |  |  |  |  |  |
|  |  |  |  | 68 | 68 | 610108300-017-G | - | RES,0 Ohm,+/-5%,1/10W,G,SMD0603 | KOA SPEER ELECTRONICS, INC. | RK73Z1JTTD | 2 | G | PECR31,PECR32 |  |  |  |  |  |  |
|  |  |  |  |  | 68 | 610108300-012-G |  | RES,0 Ohm,+/-5%,1/10W,G,SMD0603 | WALSIN TECHNOLOGY CORPORATION | WR06X000PTL |  | G |  |  |  |  |  |  |  |
|  |  |  |  |  | 68 | 610108300-011-G |  | RES,0 Ohm,+/-5%,1/10W,G,SMD0603 | YAGEO CORPORATION COMPONENT | RC0603JR-070RL |  | G |  |  |  |  |  |  |  |
|  |  |  |  |  | 68 | 610108300-044-G |  | RES,0 Ohm,+/-5%,1/10W,G,SMD0603 | TA-I TECHNOLOGY CO., LTD. | RM06JTN0 |  | G |  |  |  |  |  |  |  |
|  |  |  |  |  | 68 | 610108300-024-G |  | RES,0 Ohm,+/-5%,1/10W,G,SMD0603 | PANASONIC INDUSTRIAL CO.,LTD. | ERJ3GEY0R00V |  | G |  |  |  |  |  |  |  |
|  |  |  |  | 69 | 69 | 610113800-017-G | - | RES,10 Ohm,+/-1%,1/16W,G,SMD0402 | KOA SPEER ELECTRONICS, INC. | RK73H1ETTP10R0F | 13 | G | PFCR4,PECR33,PECR34,R105,R106,R107,R108,R109,R110,R111,R112,R113,R114 |  |  |  |  |  |  |
|  |  |  |  |  | 69 | 610113800-012-G |  | RES,10 Ohm,+/-1%,1/16W,G,SMD0402 | WALSIN TECHNOLOGY CORPORATION | WR04X10R0FTL |  | G |  |  |  |  |  |  |  |
|  |  |  |  |  | 69 | 610113800-011-G |  | RES,10 Ohm,+/-1%,1/16W,G,SMD0402 | YAGEO CORPORATION COMPONENT | RC0402FR-0710RL |  | G |  |  |  |  |  |  |  |
|  |  |  |  |  | 69 | 610113800-044-G |  | RES,10 Ohm,+/-1%,1/16W,G,SMD0402 | TA-I TECHNOLOGY CO., LTD. | RM04FTN10R0 |  | G |  |  |  |  |  |  |  |
|  |  |  |  | 70 | 70 | 61011HA00-017-G |  | RES,1 Ohm,+/-1%,1/16W,G,SMD0402 | KOA SPEER ELECTRONICS, INC. | RK73H1ETTP1R00F | 7 | G | PSCR4,PSRR5,PSLR5,PSGR5,PFCR7,PECR39,PECR40 |  |  |  |  |  |  |
|  |  |  |  |  | 70 | 61011HA00-012-G |  | RES,1 Ohm,+/-1%,1/16W,G,SMD0402 | WALSIN TECHNOLOGY CORPORATION | WR04W1R00FTL |  | G |  |  |  |  |  |  |  |
|  |  |  |  |  | 70 | 61011HA00-011-G |  | RES,1 Ohm,+/-1%,1/16W,G,SMD0402 | YAGEO CORPORATION COMPONENT | RC0402FR-071RL |  | G |  |  |  |  |  |  |  |
|  |  |  |  |  | 70 | 61011HA00-044-G |  | RES,1 Ohm,+/-1%,1/16W,G,SMD0402 | TA-I TECHNOLOGY CO., LTD. | RM04FTN1R00 |  | G |  |  |  |  |  |  |  |
|  |  |  |  |  | 70 | 61011HA00-029-G |  | RES,1 Ohm,+/-1%,1/16W,G,SMD0402 | VISHAY ENTER TECHNO LOGY.INC | CRCW04021R00FNED |  | G |  |  |  |  |  |  |  |
|  |  |  |  | 71 | 71 | 61010FE00-017-G | - | RES,100 Ohm,+/-1%,1/16W,G,SMD0402 | KOA SPEER ELECTRONICS, INC. | RK73H1ETTP1000F | 30 | G | PECR43,R73,R74,R96,R1380,R1449,R1450,R1455,R1456,R1457,R1458,R1459,R1460,R1461,R1462,R1463,R1464,R1465,R1466,R1467,R1468,R1469,R1470,R1471,R1472,R1473,R1474,R1475,R1476,R1477 |  |  |  |  |  |  |
|  |  |  |  |  | 71 | 61010FE00-012-G |  | RES,100 Ohm,+/-1%,1/16W,G,SMD0402 | WALSIN TECHNOLOGY CORPORATION | WR04X1000FTL |  | G |  |  |  |  |  |  |  |
|  |  |  |  |  | 71 | 61010FE00-011-G |  | RES,100 Ohm,+/-1%,1/16W,G,SMD0402 | YAGEO CORPORATION COMPONENT | RC0402FR-07100RL |  | G |  |  |  |  |  |  |  |
|  |  |  |  |  | 71 | 61010FE00-044-G |  | RES,100 Ohm,+/-1%,1/16W,G,SMD0402 | TA-I TECHNOLOGY CO., LTD. | RM04FTN1000 |  | G |  |  |  |  |  |  |  |
|  |  |  |  | 72 | 72 | 610125N00-017-G |  | RES,3.3 Ohm,+/-1%,1/16W,G,SMD0402 | KOA SPEER ELECTRONICS, INC. | RK73H1ETTP3R30F | 2 | G | PECR45,PECR46 |  |  |  |  |  |  |
|  |  |  |  |  | 72 | 610125N00-012-G |  | RES,3.3 Ohm,+/-1%,1/16W,G,SMD0402 | WALSIN TECHNOLOGY CORPORATION | WR04W3R30FTL |  | G |  |  |  |  |  |  |  |
|  |  |  |  |  | 72 | 610125N00-011-G |  | RES,3.3 Ohm,+/-1%,1/16W,G,SMD0402 | YAGEO CORPORATION COMPONENT | RC0402FR-073R3L |  | G |  |  |  |  |  |  |  |
|  |  |  |  |  | 72 | 610125N00-044-G |  | RES,3.3 Ohm,+/-1%,1/16W,G,SMD0402 | TA-I TECHNOLOGY CO., LTD. | RM04FTN3R30 |  | G |  |  |  |  |  |  |  |
|  |  |  |  | 73 | 73 | 610101100-017-G |  | RES,1 Ohm,+/-1%,1/10W,G,SMD0603 | KOA SPEER ELECTRONICS, INC. | RK73H1JTTD1R00F | 9 | G | PELR4,PELR11,PELR13,PFCR14,PFCR16,PECR47,PECR48,PECR49,PECR50 |  |  |  |  |  |  |
|  |  |  |  |  | 73 | 610101100-011-G |  | RES,1 Ohm,+/-1%,1/10W,G,SMD0603 | YAGEO CORPORATION COMPONENT | RC0603FR-071RL |  | G |  |  |  |  |  |  |  |
|  |  |  |  |  | 73 | 610101100-012-G |  | RES,1 Ohm,+/-1%,1/10W,G,SMD0603 | WALSIN TECHNOLOGY CORPORATION | WR06W1R00FTL |  | G |  |  |  |  |  |  |  |
|  |  |  |  |  | 73 | 610101100-044-G |  | RES,1 Ohm,+/-1%,1/10W,G,SMD0603 | TA-I TECHNOLOGY CO., LTD. | RM06FTN1R00 |  | G |  |  |  |  |  |  |  |
|  |  |  |  | 74 | 74 | 32023H600-183-G |  | IC,PWM Controller,TPS53641RSBT,G,QFN-40,SMD | TEXAS INSTRUMENTS | TPS53641RSBT | 1 | G | PECU1 |  |  |  |  |  |  |
|  |  |  |  | 75 | 75 | 320240000-183-G |  | IC,PWM Controller,CSD95472Q5MC,G,SON-13,SMD | TEXAS INSTRUMENTS | CSD95472Q5MC | 2 | G | PECU2,PECU3 |  |  |  |  |  |  |
|  |  |  |  | 76 | 76 | 62012PT00-015-G | - | CAP,22uF,+/-20%,X6S,16V,G,SMD0805 | MURATA ELEC. NORTH AMERICA | GRM21BC81C226M | 15 | G | PSRC7,PLTC7,PSRC8,PLTC8,PLTC9,PLTC10,PSRC11,PSRC12,PELC12,PELC13,PELC14,PSRC15,PELC15,PELC18,PELC19 |  |  |  |  |  |  |
|  |  |  |  |  | 76 | 62012PT00-023-G |  | CAP,22uF,+/-20%,X6S,16V,G,SMD0805 | TAIYO ELECTRIC IND.CO.LTD | EDK212BC6226MG-T |  | G |  |  |  |  |  |  |  |
|  |  |  |  | 77 | 77 | 62011G000-015-G | - | CAP,1uF,+/-10%,X5R,16V,G,SMD0402 | MURATA ELEC. NORTH AMERICA | GRM155R61C105K | 1 | G | PELC16 |  |  |  |  |  |  |
|  |  |  |  |  | 77 | 62011G000-026-G |  | CAP,1uF,+/-10%,X5R,16V,G,SMD0402 | SAMSUNG SEMICONDUCTOR | CL05A105KO5NNNC |  | G |  |  |  |  |  |  |  |
|  |  |  |  |  | 77 | 62011G000-023-G |  | CAP,1uF,+/-10%,X5R,16V,G,SMD0402 | TAIYO ELECTRIC IND.CO.LTD | EMK105BJ105KV-F |  | G |  |  |  |  |  |  |  |
|  |  |  |  |  | 77 | 62011G000-012-G |  | CAP,1uF,+/-10%,X5R,16V,G,SMD0402 | WALSIN TECHNOLOGY CORPORATION | 0402X105K160CT |  | G |  |  |  |  |  |  |  |
|  |  |  |  | 78 | 78 | 72010SJ00-059-G |  | FB,Multilayer,10mOhm,26Ohm@100MHz,+/-25%,6A,,SMD0603,G | TAI-TECH ADVANCED ELECTRONICS CO., LTD. | HCB1608KF-260T60 | 8 | G | PSRL1,PSLL1,PSGL1,PLTL1,PFCL1,PELL1,PELL3,PELL4 |  |  |  |  |  |  |
|  |  |  |  | 79 | 79 | 63033RJ00-15A-G |  | IND,4.7uH@100KHz,+/-20%,3.5A,65mOhm,SHLD,G,SMD | The Inter-Technical Group, Inc. | SMHC2011-4R7MHF | 1 | G | PELL2 |  |  |  |  |  |  |
|  |  |  |  | 80 | 80 | 611003200-011-G |  | RES,10KOhm,+/-0.1%,1/16W,G,SMD0402 | YAGEO CORPORATION COMPONENT | RT0402BRE0710KL | 2 | G | PELR3,PFCR5 |  |  |  |  |  |  |
|  |  |  |  | 81 | 81 | 61100UT00-011-G |  | RES,20.5KOhm,+/-0.1%,1/16W,G,SMD0402 | YAGEO CORPORATION COMPONENT | RT0402BRD0720K5L | 1 | G | PELR5 |  |  |  |  |  |  |
|  |  |  |  | 82 | 82 | 61010LA00-017-G | - | RES,4.7KOhm,+/-1%,1/16W,G,SMD0402 | KOA SPEER ELECTRONICS, INC. | RK73H1ETTP4701F | 8 | G | PSCR1,PELR6,PFCR8,R229,R230,R251,R252,R1539 |  |  |  |  |  |  |
|  |  |  |  |  | 82 | 61010LA00-012-G |  | RES,4.7KOhm,+/-1%,1/16W,G,SMD0402 | WALSIN TECHNOLOGY CORPORATION | WR04X4701FTL |  | G |  |  |  |  |  |  |  |
|  |  |  |  |  | 82 | 61010LA00-011-G |  | RES,4.7KOhm,+/-1%,1/16W,G,SMD0402 | YAGEO CORPORATION COMPONENT | RC0402FR-074K7L |  | G |  |  |  |  |  |  |  |
|  |  |  |  |  | 82 | 61010LA00-044-G |  | RES,4.7KOhm,+/-1%,1/16W,G,SMD0402 | TA-I TECHNOLOGY CO., LTD. | RM04FTN4701 |  | G |  |  |  |  |  |  |  |
|  |  |  |  | 83 | 83 | 61011UM00-017-G | - | RES,240KOhm,+/-1%,1/16W,G,SMD0402 | KOA SPEER ELECTRONICS, INC. | RK73H1ETTP2403F | 2 | G | PELR12,PFCR13 |  |  |  |  |  |  |
|  |  |  |  |  | 83 | 61011UM00-011-G |  | RES,240KOhm,+/-1%,1/16W,G,SMD0402 | YAGEO CORPORATION COMPONENT | RC0402FR-07240KL |  | G |  |  |  |  |  |  |  |
|  |  |  |  |  | 83 | 61011UM00-012-G |  | RES,240KOhm,+/-1%,1/16W,G,SMD0402 | WALSIN TECHNOLOGY CORPORATION | WR04X2403FTL |  | G |  |  |  |  |  |  |  |
|  |  |  |  |  | 83 | 61011UM00-044-G |  | RES,240KOhm,+/-1%,1/16W,G,SMD0402 | TA-I TECHNOLOGY CO., LTD. | RM04FTN2403 |  | G |  |  |  |  |  |  |  |
|  |  |  |  | 84 | 84 | 61011YJ00-017-G |  | RES,71.5KOhm,+/-1%,1/16W,G,SMD0402 | KOA SPEER ELECTRONICS, INC. | RK73H1ETTP7152F | 2 | G | PELR14,PFCR15 |  |  |  |  |  |  |
|  |  |  |  |  | 84 | 61011YJ00-011-G |  | RES,71.5KOhm,+/-1%,1/16W,G,SMD0402 | YAGEO CORPORATION COMPONENT | RC0402FR-0771K5L |  | G |  |  |  |  |  |  |  |
|  |  |  |  |  | 84 | 61011YJ00-012-G |  | RES,71.5KOhm,+/-1%,1/16W,G,SMD0402 | WALSIN TECHNOLOGY CORPORATION | WR04X7152FTL |  | G |  |  |  |  |  |  |  |
|  |  |  |  |  | 84 | 61011YJ00-044-G |  | RES,71.5KOhm,+/-1%,1/16W,G,SMD0402 | TA-I TECHNOLOGY CO., LTD. | RM04FTN7152 |  | G |  |  |  |  |  |  |  |
|  |  |  |  | 85 | 85 | 32013BY00-183-G |  | IC,Regulator,TPS53513RVER,8A,ADJ,G,QFN-28,SMD | TEXAS INSTRUMENTS | TPS53513RVER | 1 | G | PELU1 |  |  |  |  |  |  |
|  |  |  |  | 86 | 86 | 63033JL00-15A-G |  | IND,470nH@100KHz,+/-20%,13.5A,4.2mOhm,SHLD,G,SMD | The Inter-Technical Group, Inc. | SMHC2511-R47MHF | 1 | G | PFCL2 |  |  |  |  |  |  |
|  |  |  |  | 87 | 87 | 610116N00-017-G |  | RES,5.1KOhm,+/-1%,1/16W,G,SMD0402 | KOA SPEER ELECTRONICS, INC. | RK73H1ETTP5101F | 1 | G | PFCR6 |  |  |  |  |  |  |
|  |  |  |  |  | 87 | 610116N00-011-G |  | RES,5.1KOhm,+/-1%,1/16W,G,SMD0402 | YAGEO CORPORATION COMPONENT | RC0402FR-075K1L |  | G |  |  |  |  |  |  |  |
|  |  |  |  |  | 87 | 610116N00-012-G |  | RES,5.1KOhm,+/-1%,1/16W,G,SMD0402 | WALSIN TECHNOLOGY CORPORATION | WR04X5101FTL |  | G |  |  |  |  |  |  |  |
|  |  |  |  |  | 87 | 610116N00-044-G |  | RES,5.1KOhm,+/-1%,1/16W,G,SMD0402 | TA-I TECHNOLOGY CO., LTD. | RM04FTN5101 |  | G |  |  |  |  |  |  |  |
|  |  |  |  | 88 | 88 | 61011VM00-017-G | - | RES,57.6KOhm,+/-1%,1/16W,G,SMD0402 | KOA SPEER ELECTRONICS, INC. | RK73H1ETTP5762F | 1 | G | PFCR12 |  |  |  |  |  |  |
|  |  |  |  |  | 88 | 61011VM00-011-G |  | RES,57.6KOhm,+/-1%,1/16W,G,SMD0402 | YAGEO CORPORATION COMPONENT | RC0402FR-0757K6L |  | G |  |  |  |  |  |  |  |
|  |  |  |  |  | 88 | 61011VM00-012-G |  | RES,57.6KOhm,+/-1%,1/16W,G,SMD0402 | WALSIN TECHNOLOGY CORPORATION | WR04X5762FTL |  | G |  |  |  |  |  |  |  |
|  |  |  |  |  | 88 | 61011VM00-044-G |  | RES,57.6KOhm,+/-1%,1/16W,G,SMD0402 | TA-I TECHNOLOGY CO., LTD. | RM04FTN5762 |  | G |  |  |  |  |  |  |  |
|  |  |  |  | 89 | 89 | 320143Y00-183-G | - | IC,Regulator,TPS548A20RVER,ADJ,15A,G,VQFN-28,SMD | TEXAS INSTRUMENTS | TPS548A20RVER | 1 | G | PFCU1 |  |  |  |  |  |  |
|  |  |  |  | 90 | 90 | 62012T500-015-G |  | CAP,22uF,+/-20%,X7S,25V,G,SMD1206 | MURATA ELEC. NORTH AMERICA | GRM31CC71E226ME11L | 18 | G | PSRC2,PSLC2,PSGC2,PLTC2,PLTC3,PSCC6,PSCC7,PSCC8,PSCC9,PSRC17,PSLC17,PSGC17,PSRC18,PSLC18,PSGC18,PSRC19,PSCC3005,PSCC3009 |  |  |  |  |  |  |
|  |  |  |  | 91 | 91 | 61011FG00-017-G |  | RES,107KOhm,+/-1%,1/16W,G,SMD0402 | KOA SPEER ELECTRONICS, INC. | RK73H1ETTP1073F | 1 | G | PLTR2 |  |  |  |  |  |  |
|  |  |  |  |  | 91 | 61011FG00-012-G |  | RES,107KOhm,+/-1%,1/16W,G,SMD0402 | WALSIN TECHNOLOGY CORPORATION | WR04X1073FTL |  | G |  |  |  |  |  |  |  |
|  |  |  |  |  | 91 | 61011FG00-011-G |  | RES,107KOhm,+/-1%,1/16W,G,SMD0402 | YAGEO CORPORATION COMPONENT | RC0402FR-07107KL |  | G |  |  |  |  |  |  |  |
|  |  |  |  |  | 91 | 61011FG00-044-G |  | RES,107KOhm,+/-1%,1/16W,G,SMD0402 | TA-I TECHNOLOGY CO., LTD. | RM04FTN1073 |  | G |  |  |  |  |  |  |  |
|  |  |  |  | 92 | 92 | 610118700-017-G |  | RES,51.1KOhm,+/-1%,1/16W,G,SMD0402 | KOA SPEER ELECTRONICS, INC. | RK73H1ETTP5112F | 1 | G | PLTR3 |  |  |  |  |  |  |
|  |  |  |  |  | 92 | 610118700-012-G |  | RES,51.1KOhm,+/-1%,1/16W,G,SMD0402 | WALSIN TECHNOLOGY CORPORATION | WR04X5112FTL |  | G |  |  |  |  |  |  |  |
|  |  |  |  |  | 92 | 610118700-011-G |  | RES,51.1KOhm,+/-1%,1/16W,G,SMD0402 | YAGEO CORPORATION COMPONENT | RC0402FR-0751K1L |  | G |  |  |  |  |  |  |  |
|  |  |  |  |  | 92 | 610118700-044-G |  | RES,51.1KOhm,+/-1%,1/16W,G,SMD0402 | TA-I TECHNOLOGY CO., LTD. | RM04FTN5112 |  | G |  |  |  |  |  |  |  |
|  |  |  |  | 93 | 93 | 611004M00-024-G |  | RES,16.5KOhm,+/-0.1%,1/16W,G,SMD0402 | PANASONIC INDUSTRIAL CO.,LTD. | ERA2AEB1652X | 3 | G | PLTR4,PSRR17,PSLR17 |  |  |  |  |  |  |
|  |  |  |  | 94 | 94 | 610119P00-017-G | - | RES,5.11KOhm,+/-1%,1/16W,G,SMD0402 | KOA SPEER ELECTRONICS, INC. | RK73H1ETTP5111F | 1 | G | PLTR5 |  |  |  |  |  |  |
|  |  |  |  |  | 94 | 610119P00-012-G |  | RES,5.11KOhm,+/-1%,1/16W,G,SMD0402 | WALSIN TECHNOLOGY CORPORATION | WR04X5111FTL |  | G |  |  |  |  |  |  |  |
|  |  |  |  |  | 94 | 610119P00-011-G |  | RES,5.11KOhm,+/-1%,1/16W,G,SMD0402 | YAGEO CORPORATION COMPONENT | RC0402FR-075K11L |  | G |  |  |  |  |  |  |  |
|  |  |  |  |  | 94 | 610119P00-024-G |  | RES,5.11KOhm,+/-1%,1/16W,G,SMD0402 | PANASONIC INDUSTRIAL CO.,LTD. | ERJ2RKF5111X |  | G |  |  |  |  |  |  |  |
|  |  |  |  |  | 94 | 610119P00-029-G |  | RES,5.11KOhm,+/-1%,1/16W,G,SMD0402 | VISHAY ENTER TECHNO LOGY.INC | CRCW04025K11FKED |  | G |  |  |  |  |  |  |  |
|  |  |  |  | 95 | 95 | 320128V00-183-G |  | IC,Regulator,TPS73801DCQR,1A,ADJ,G,SOT223-5,SMD | TEXAS INSTRUMENTS | TPS73801DCQR | 1 | G | PLTU1 |  |  |  |  |  |  |
|  |  |  |  | 96 | 96 | 62120CM00-024-G | - | SPEA CAP,220uF,+10%~-35%,6.3V,105C,G,SMD2816,ESR<=15mOhm | PANASONIC INDUSTRIAL CO.,LTD. | EEFCX0J221YR | 2 | G | PSCCE3003,PSCCE3004 |  |  |  |  |  |  |
|  |  |  |  | 97 | 97 | 62012GF00-015-G | - | CAP,22uF,+/-20%,X6S,6.3V,G,SMD0603 | MURATA ELEC. NORTH AMERICA | GRM188C80J226M | 6 | G | PSCC2,PSCC3,PSCC3000,PSCC3010,PSCC3011,PSCC3012 |  |  |  |  |  |  |
|  |  |  |  |  | 97 | 62012GF00-023-G |  | CAP,22uF,+/-20%,X6S,6.3V,G,SMD0603 | TAIYO ELECTRIC IND.CO.LTD | JDK107BC6226MA-T |  | G |  |  |  |  |  |  |  |
|  |  |  |  | 98 | 98 | 620108000-015-G | - | CAP,100pF,+/-5%,NPO(C0G),50V,G,SMD0402 | MURATA ELEC. NORTH AMERICA | GRM1555C1H101J | 3 | G | PSCC4,PSLC14,PSGC14 |  |  |  |  |  |  |
|  |  |  |  |  | 98 | 62010800A-012-G |  | CAP,100pF,+/-5%,NPO(C0G),50V,G,SMD0402 | WALSIN TECHNOLOGY CORPORATION | 0402N101J500CT |  | G |  |  |  |  |  |  |  |
|  |  |  |  |  | 98 | 620108000-026-G |  | CAP,100pF,+/-5%,NPO(C0G),50V,G,SMD0402 | SAMSUNG SEMICONDUCTOR | CL05C101JB5NNNC |  | G |  |  |  |  |  |  |  |
|  |  |  |  |  | 98 | 620108000-023-G |  | CAP,100pF,+/-5%,NPO(C0G),50V,G,SMD0402 | TAIYO ELECTRIC IND.CO.LTD | UMK105CG101JV-F |  | G |  |  |  |  |  |  |  |
|  |  |  |  | 99 | 99 | 62013BS00-015-G |  | CAP,3nF,+/-10%,X7R,50V,G,SMD0402 | MURATA ELEC. NORTH AMERICA | GRM155R71H302KA01D | 1 | G | PSCC10 |  |  |  |  |  |  |
|  |  |  |  |  | 99 | 62013BS00-012-G |  | CAP,3nF,+/-10%,X7R,50V,G,SMD0402 | WALSIN TECHNOLOGY CORPORATION | 0402B302K500CT |  | G |  |  |  |  |  |  |  |
|  |  |  |  | 100 | 100 | 62010FF00-015-G | - | CAP,47pF,+/-5%,NPO(C0G),50V,G,SMD0402 | MURATA ELEC. NORTH AMERICA | GRM1555C1H470J | 1 | G | PSCC11 |  |  |  |  |  |  |
|  |  |  |  |  | 100 | 62010FF06-012-G |  | CAP,47pF,+/-5%,NPO(C0G),50V,G,SMD0402 | WALSIN TECHNOLOGY CORPORATION | 0402N470J500CT |  | G |  |  |  |  |  |  |  |
|  |  |  |  |  | 100 | 62010FF00-026-G |  | CAP,47pF,+/-5%,NPO(C0G),50V,G,SMD0402 | SAMSUNG SEMICONDUCTOR | CL05C470JB5NNNC |  | G |  |  |  |  |  |  |  |
|  |  |  |  |  | 100 | 62010FF00-023-G |  | CAP,47pF,+/-5%,NPO(C0G),50V,G,SMD0402 | TAIYO ELECTRIC IND.CO.LTD | UMK105CG470JV-F |  | G |  |  |  |  |  |  |  |
|  |  |  |  | 101 | 101 | 620107L00-015-G | - | CAP,2.2nF,+/-10%,X7R,50V,G,SMD0402 | MURATA ELEC. NORTH AMERICA | GRM155R71H222K | 1 | G | PSCC12 |  |  |  |  |  |  |
|  |  |  |  |  | 101 | 620107L00-012-G |  | CAP,2.2nF,+/-10%,X7R,50V,G,SMD0402 | WALSIN TECHNOLOGY CORPORATION | 0402B222K500CT |  | G |  |  |  |  |  |  |  |
|  |  |  |  |  | 101 | 620107L00-026-G |  | CAP,2.2nF,+/-10%,X7R,50V,G,SMD0402 | SAMSUNG SEMICONDUCTOR | CL05B222KB5NNNC |  | G |  |  |  |  |  |  |  |
|  |  |  |  |  | 101 | 620107L03-023-G |  | CAP,2.2nF,+/-10%,X7R,50V,G,SMD0402 | TAIYO ELECTRIC IND.CO.LTD | UMK105B7222KV-F |  | G |  |  |  |  |  |  |  |
|  |  |  |  | 102 | 102 | 62012T300-015-G | - | CAP,1uF,+/-10%,X7S,25V,G,SMD0402 | MURATA ELEC. NORTH AMERICA | GRM155C71E105KE11D | 4 | G | PSRC4,PSLC4,PSGC4,PSCC3003 |  |  |  |  |  |  |
|  |  |  |  |  | 102 | 620138700-026-G |  | CAP,1uF,+/-10%,X6S,25V,G,SMD0402 | SAMSUNG SEMICONDUCTOR | CL05X105KA5NQNC |  | G |  |  |  |  |  |  |  |
|  |  |  |  |  | 102 | 620138700-015-G |  | CAP,1uF,+/-10%,X6S,25V,G,SMD0402 | MURATA ELEC. NORTH AMERICA | GRM155C81E105KE11D |  | G |  |  |  |  |  |  |  |
|  |  |  |  | 103 | 103 | 63034UP00-15A-G |  | IND,220nH@100KHz,+/-20%,23A,2.8mOhm,SHLD,G,SMD | The Inter-Technical Group, Inc. | SMHC2511-R22MHF | 1 | G | PSCL1 |  |  |  |  |  |  |
|  |  |  |  | 104 | 104 | 630362G00-065-G |  | IND,22nH@100KHz,+/-20%,19A,0.32mOhm,SHLD,G,SMD | DELTA ELECTRONICS INDUSTRIAL CO.,LTD | HCB0430-220 | 1 | G | PSCL2 |  |  |  |  |  |  |
|  |  |  |  | 105 | 105 | 61100J300-011-G |  | RES,121 Ohm,+/-0.1%,1/16W,G,SMD0402 | YAGEO CORPORATION COMPONENT | RT0402BRD07121RL | 1 | G | PSCR5 |  |  |  |  |  |  |
|  |  |  |  | 106 | 106 | 61100U300-011-G |  | RES,210 Ohm,+/-0.1%,1/16W,G,SMD0402 | YAGEO CORPORATION COMPONENT | RT0402BRD07210RL | 1 | G | PSCR6 |  |  |  |  |  |  |
|  |  |  |  | 107 | 107 | 61011C400-017-G | - | RES,4.32KOhm,+/-1%,1/16W,G,SMD0402 | KOA SPEER ELECTRONICS, INC. | RK73H1ETTP4321F | 1 | G | PSCR10 |  |  |  |  |  |  |
|  |  |  |  |  | 107 | 61011C400-012-G |  | RES,4.32KOhm,+/-1%,1/16W,G,SMD0402 | WALSIN TECHNOLOGY CORPORATION | WR04X4321FTL |  | G |  |  |  |  |  |  |  |
|  |  |  |  |  | 107 | 61011C400-011-G |  | RES,4.32KOhm,+/-1%,1/16W,G,SMD0402 | YAGEO CORPORATION COMPONENT | RC0402FR-074K32L |  | G |  |  |  |  |  |  |  |
|  |  |  |  |  | 107 | 61011C400-044-G |  | RES,4.32KOhm,+/-1%,1/16W,G,SMD0402 | TA-I TECHNOLOGY CO., LTD. | RM04FTN4321 |  | G |  |  |  |  |  |  |  |
|  |  |  |  | 108 | 108 | 610112J00-017-G | - | RES,200 Ohm,+/-1%,1/16W,G,SMD0402 | KOA SPEER ELECTRONICS, INC. | RK73H1ETTP2000F | 1 | G | PSCR11 |  |  |  |  |  |  |
|  |  |  |  |  | 108 | 610112J00-012-G |  | RES,200 Ohm,+/-1%,1/16W,G,SMD0402 | WALSIN TECHNOLOGY CORPORATION | WR04X2000FTL |  | G |  |  |  |  |  |  |  |
|  |  |  |  |  | 108 | 610112J00-011-G |  | RES,200 Ohm,+/-1%,1/16W,G,SMD0402 | YAGEO CORPORATION COMPONENT | RC0402FR-07200RL |  | G |  |  |  |  |  |  |  |
|  |  |  |  |  | 108 | 610112J00-044-G |  | RES,200 Ohm,+/-1%,1/16W,G,SMD0402 | TA-I TECHNOLOGY CO., LTD. | RM04FTN2000 |  | G |  |  |  |  |  |  |  |
|  |  |  |  |  | 108 | 610112J00-029-G |  | RES,200 Ohm,+/-1%,1/16W,G,SMD0402 | VISHAY ENTER TECHNO LOGY.INC | CRCW0402200RFKED |  | G |  |  |  |  |  |  |  |
|  |  |  |  |  | 108 | 610112J00-024-G |  | RES,200 Ohm,+/-1%,1/16W,G,SMD0402 | PANASONIC INDUSTRIAL CO.,LTD. | ERJ2RKF2000X |  | G |  |  |  |  |  |  |  |
|  |  |  |  | 109 | 109 | 61011JY00-017-G | - | RES,39.2KOhm,+/-1%,1/16W,G,SMD0402 | KOA SPEER ELECTRONICS, INC. | RK73H1ETTP3922F | 1 | G | PSCR15 |  |  |  |  |  |  |
|  |  |  |  |  | 109 | 61011JY00-012-G |  | RES,39.2KOhm,+/-1%,1/16W,G,SMD0402 | WALSIN TECHNOLOGY CORPORATION | WR04X3922FTL |  | G |  |  |  |  |  |  |  |
|  |  |  |  |  | 109 | 61011JY00-011-G |  | RES,39.2KOhm,+/-1%,1/16W,G,SMD0402 | YAGEO CORPORATION COMPONENT | RC0402FR-0739K2L |  | G |  |  |  |  |  |  |  |
|  |  |  |  |  | 109 | 61011JY00-044-G |  | RES,39.2KOhm,+/-1%,1/16W,G,SMD0402 | TA-I TECHNOLOGY CO., LTD. | RM04FTN3922 |  | G |  |  |  |  |  |  |  |
|  |  |  |  |  | 109 | 61011JY00-029-G |  | RES,39.2KOhm,+/-1%,1/16W,G,SMD0402 | VISHAY ENTER TECHNO LOGY.INC | CRCW040239K2FKED |  | G |  |  |  |  |  |  |  |
|  |  |  |  | 110 | 110 | 61011RF00-017-G |  | RES,1.8KOhm,+/-1%,1/8W,G,SMD0805 | KOA SPEER ELECTRONICS, INC. | RK73H2ATTD1801F | 2 | G | PSGR20,PSCR3000 |  |  |  |  |  |  |
|  |  |  |  |  | 110 | 61011RF00-011-G |  | RES,1.8KOhm,+/-1%,1/8W,G,SMD0805 | YAGEO CORPORATION COMPONENT | RC0805FR-071K8L |  | G |  |  |  |  |  |  |  |
|  |  |  |  |  | 110 | 61011RF00-012-G |  | RES,1.8KOhm,+/-1%,1/8W,G,SMD0805 | WALSIN TECHNOLOGY CORPORATION | WR08X1801FTL |  | G |  |  |  |  |  |  |  |
|  |  |  |  | 111 | 111 | 32013HH00-238-G |  | IC,Regulator,IR3447MTRPBF,ADJ,25A,G,PQFN-33 | INTERNATIONAL RECTIFIER | IR3447MTRPBF | 1 | G | PSCU1 |  |  |  |  |  |  |
|  |  |  |  | 112 | 112 | 62012CM01-015-G |  | CAP,10uF,+/-20%,X6S,4V,G,SMD0603 | MURATA ELEC. NORTH AMERICA | GRM188C80G106M | 2 | G | PSLC16,PSGC16 |  |  |  |  |  |  |
|  |  |  |  |  | 112 | 62012CM00-023-G |  | CAP,10uF,+/-20%,X6S,4V,G,SMD0603 | TAIYO ELECTRIC IND.CO.LTD | AMK107AC6106MA-T |  | G |  |  |  |  |  |  |  |
|  |  |  |  |  | 112 | 62012CM00-026-G |  | CAP,10uF,+/-20%,X6S,4V,G,SMD0603 | SAMSUNG SEMICONDUCTOR | CL10X106MR8NNNC |  | G |  |  |  |  |  |  |  |
|  |  |  |  | 113 | 113 | 63032CD00-088-G | - | IND,2.2uH@100KHz,+/-20%,8A,20mOhm,SHLD,G,SMD | COOPER BUSSMANN, INC. | HCM0703-2R2-R | 1 | G | PSGL2 |  |  |  |  |  |  |
|  |  |  |  | 114 | 114 | 61010G500-017-G | - | RES,10KOhm,+/-1%,1/16W,G,SMD0402 | KOA SPEER ELECTRONICS, INC. | RK73H1ETTP1002F | 62 | G | PSRR6,PSLR6,PSGR6,R18,R40,R41,R42,R43,R44,R45,R46,R89,R90,R91,R102,R103,R104,R127,R128,R129,R130,R134,R139,R141,R234,R248,R342,R343,R344,R345,R346,R347,R348,R349,R350,R351,R352,R353,R354,R355,R356,R357,R358,R359,R360,R361,R371,R397,R398,R404,R405,R406,R407,R442,R443,R1487,R1493,R1497,R1501,R1511,R1512,R1544, |  |  |  |  |  |  |
|  |  |  |  |  | 114 | 61010G500-012-G |  | RES,10KOhm,+/-1%,1/16W,G,SMD0402 | WALSIN TECHNOLOGY CORPORATION | WR04X1002FTL |  | G |  |  |  |  |  |  |  |
|  |  |  |  |  | 114 | 61010G500-011-G |  | RES,10KOhm,+/-1%,1/16W,G,SMD0402 | YAGEO CORPORATION COMPONENT | RC0402FR-0710KL |  | G |  |  |  |  |  |  |  |
|  |  |  |  |  | 114 | 61010G500-044-G |  | RES,10KOhm,+/-1%,1/16W,G,SMD0402 | TA-I TECHNOLOGY CO., LTD. | RM04FTN1002 |  | G |  |  |  |  |  |  |  |
|  |  |  |  |  | 114 | 61010G500-029-G |  | RES,10KOhm,+/-1%,1/16W,G,SMD0402 | VISHAY ENTER TECHNO LOGY.INC | CRCW040210K0FKED |  | G |  |  |  |  |  |  |  |
|  |  |  |  |  | 114 | 61010G500-024-G |  | RES,10KOhm,+/-1%,1/16W,G,SMD0402 | PANASONIC INDUSTRIAL CO.,LTD. | ERJ2RKF1002X |  | G |  |  |  |  |  |  |  |
|  |  |  |  | 115 | 115 | 61100QY00-017-G |  | RES,17.4KOhm,+/-0.1%,1/16W,G,SMD0402 | KOA SPEER ELECTRONICS, INC. | RN731ETTP1742B25 | 1 | G | PSGR17 |  |  |  |  |  |  |
|  |  |  |  | 116 | 116 | 61100PL00-017-G |  | RES,10.2KOhm,+/-0.1%,1/16W,G,SMD0402 | KOA SPEER ELECTRONICS, INC. | RN731ETTP1022B25 | 1 | G | PSGR19 |  |  |  |  |  |  |
|  |  |  |  | 117 | 117 | 32013PD00-238-G |  | IC,Regulator,IR3883MTRPbF,ADJ,3A,G,QFN-16,SMD | INTERNATIONAL RECTIFIER | IR3883MTRPBF | 3 | G | PSRU1,PSLU1,PSGU1 |  |  |  |  |  |  |
|  |  |  |  | 118 | 118 | 63034QP00-034-G |  | IND,3.3uH@100KHz,+/-20%,6.5A,21mOhm,SHLD,G,SMD | CYNTEC CO. LTD | PCME063T-3R3MS | 1 | G | PSLL2 |  |  |  |  |  |  |
|  |  |  |  | 119 | 119 | 61100DF00-011-G |  | RES,6.34KOhm,+/-0.1%,1/16W,G,SMD0402 | YAGEO CORPORATION COMPONENT | RT0402BRD076K34L | 1 | G | PSLR19 |  |  |  |  |  |  |
|  |  |  |  | 120 | 120 | 620105U00-015-G | - | CAP,220pF,+/-10%,X7R,50V,G,SMD0402 | MURATA ELEC. NORTH AMERICA | GRM155R71H221K | 1 | G | PSRC14 |  |  |  |  |  |  |
|  |  |  |  |  | 120 | 620105U00-012-G |  | CAP,220pF,+/-10%,X7R,50V,G,SMD0402 | WALSIN TECHNOLOGY CORPORATION | 0402B221K500CT |  | G |  |  |  |  |  |  |  |
|  |  |  |  |  | 120 | 620105U00-026-G |  | CAP,220pF,+/-10%,X7R,50V,G,SMD0402 | SAMSUNG SEMICONDUCTOR | CL05B221KB5NNNC |  | G |  |  |  |  |  |  |  |
|  |  |  |  | 121 | 121 | 63030PW00-034-G |  | Coil Ind,Shielded(SHLD),4.7uH@100KHz,+/-20%,5.5A,40mOhm,SMD,7.3*6.6*3.0,G | CYNTEC CO. LTD | PCMC063T-4R7MN | 1 | G | PSRL2 |  |  |  |  |  |  |
|  |  |  |  | 122 | 122 | 610117D00-017-G | - | RES,13.3KOhm,+/-1%,1/16W,G,SMD0402 | KOA SPEER ELECTRONICS, INC. | RK73H1ETTP1332F | 1 | G | PSRR1 |  |  |  |  |  |  |
|  |  |  |  |  | 122 | 610117D00-012-G |  | RES,13.3KOhm,+/-1%,1/16W,G,SMD0402 | WALSIN TECHNOLOGY CORPORATION | WR04X1332FTL |  | G |  |  |  |  |  |  |  |
|  |  |  |  |  | 122 | 610117D00-011-G |  | RES,13.3KOhm,+/-1%,1/16W,G,SMD0402 | YAGEO CORPORATION COMPONENT | RC0402FR-0713K3L |  | G |  |  |  |  |  |  |  |
|  |  |  |  |  | 122 | 610117D00-044-G |  | RES,13.3KOhm,+/-1%,1/16W,G,SMD0402 | TA-I TECHNOLOGY CO., LTD. | RM04FTN1332 |  | G |  |  |  |  |  |  |  |
|  |  |  |  | 123 | 123 | 61100YB00-011-G |  | RES,2.94KOhm,+/-0.1%,1/16W,G,SMD0402 | YAGEO CORPORATION COMPONENT | RT0402BRD072K94L | 1 | G | PSRR19 |  |  |  |  |  |  |
|  |  |  |  | 124 | 124 | 51050L500-029-G |  | MOS,N/N,Si1034CX-T1-GE3,20V,0.61A,G,SC-89-6,SMD | VISHAY ENTER TECHNO LOGY.INC | Si1034CX-T1-GE3 | 4 | G | QN1,QN2,QN3,QN5 |  |  |  |  |  |  |
|  |  |  |  | 125 | 125 | 51050HV00-031-G |  | FET Dual channel,NX7002BKS,60V,240mA,2.8Ohm@Vgs=10V,3.2Ohm@Vgs=5V,SOT-363,6P,G | NXP SEMICONDUCTORS | NX7002BKS | 1 | G | QN4 |  |  |  |  |  |  |
|  |  |  |  | 126 | 126 | 510302R00-185-G |  | MOS N,BSS138,50V,0.22A,6ohm@4.5V,G,SOT23-3,SMD | FAIRCHILD SEMICONDUCTOR CORP | BSS138 | 5 | G | Q1,Q2,Q3,Q8,Q9 |  |  |  |  |  |  |
|  |  |  |  | 127 | 127 | 51040ME00-262-G |  | MOS P,AON6403L,30V,85A,4.3m@4.5V,G,DFN-8,SMD | Alpha & Omega Semiconductor Inc. | AON6403L | 2 | G | Q4,Q6 |  |  |  |  |  |  |
|  |  |  |  | 128 | 128 | 51031D300-221-G |  | MOS N,BSZ0909NS,34V,36A,15m@4.5V,G,SON-8,SMD | INFINEON TECHNOLOGIES CORP. | BSZ0909NS | 1 | G | Q5 |  |  |  |  |  |  |
|  |  |  |  | 129 | 129 | 510301N00-223-G |  | MOS N,2N7002LT1G,60V,0.115A,7.5ohm@5V,G,SOT23-3,SMD | ON SEMICONDUCTOR CORP | 2N7002LT1G | 1 | G | Q7 |  |  |  |  |  |  |
|  |  |  |  | 130 | 130 | 61010H800-017-G |  | RES,5.11 Ohm,+/-1%,1/10W,G,SMD0603 | KOA SPEER ELECTRONICS, INC. | RK73H1JTTD5R11F | 1 | G | R4 |  |  |  |  |  |  |
|  |  |  |  |  | 130 | 61010H800-012-G |  | RES,5.11 Ohm,+/-1%,1/10W,G,SMD0603 | WALSIN TECHNOLOGY CORPORATION | WR06W5R11FTL |  | G |  |  |  |  |  |  |  |
|  |  |  |  |  | 130 | 61010H800-011-G |  | RES,5.11 Ohm,+/-1%,1/10W,G,SMD0603 | YAGEO CORPORATION COMPONENT | RC0603FR-075R11L |  | G |  |  |  |  |  |  |  |
|  |  |  |  |  | 130 | 61010H800-044-G |  | RES,5.11 Ohm,+/-1%,1/10W,G,SMD0603 | TA-I TECHNOLOGY CO., LTD. | RM06FTN5R11 |  | G |  |  |  |  |  |  |  |
|  |  |  |  | 131 | 131 | 61011MQ00-017-G | - | RES,4.75KOhm,+/-1%,1/16W,G,SMD0402 | KOA SPEER ELECTRONICS, INC. | RK73H1ETTP4751F | 15 | G | R5,R28,R30,R34,R36,R78,R84,R92,R188,R195,R210,R211,R241,R242,R1446 |  |  |  |  |  |  |
|  |  |  |  |  | 131 | 61011MQ00-011-G |  | RES,4.75KOhm,+/-1%,1/16W,G,SMD0402 | YAGEO CORPORATION COMPONENT | RC0402FR-074K75L |  | G |  |  |  |  |  |  |  |
|  |  |  |  |  | 131 | 61011MQ00-012-G |  | RES,4.75KOhm,+/-1%,1/16W,G,SMD0402 | WALSIN TECHNOLOGY CORPORATION | WR04X4751FTL |  | G |  |  |  |  |  |  |  |
|  |  |  |  |  | 131 | 61011MQ00-044-G |  | RES,4.75KOhm,+/-1%,1/16W,G,SMD0402 | TA-I TECHNOLOGY CO., LTD. | RM04FTN4751 |  | G |  |  |  |  |  |  |  |
|  |  |  |  | 132 | 132 | 61011KB00-017-G | - | RES,51.1 Ohm,+/-1%,1/16W,G,SMD0402 | KOA SPEER ELECTRONICS, INC. | RK73H1ETTP51R1F | 4 | G | R6,R8,R9,R10 |  |  |  |  |  |  |
|  |  |  |  |  | 132 | 61011KB00-011-G |  | RES,51.1 Ohm,+/-1%,1/16W,G,SMD0402 | YAGEO CORPORATION COMPONENT | RC0402FR-0751R1L |  | G |  |  |  |  |  |  |  |
|  |  |  |  |  | 132 | 61011KB00-012-G |  | RES,51.1 Ohm,+/-1%,1/16W,G,SMD0402 | WALSIN TECHNOLOGY CORPORATION | WR04X51R1FTL |  | G |  |  |  |  |  |  |  |
|  |  |  |  |  | 132 | 61011KB00-044-G |  | RES,51.1 Ohm,+/-1%,1/16W,G,SMD0402 | TA-I TECHNOLOGY CO., LTD. | RM04FTN51R1 |  | G |  |  |  |  |  |  |  |
|  |  |  |  | 133 | 133 | 61011BH00-017-G |  | RES,22.1 Ohm,+/-1%,1/16W,G,SMD0402 | KOA SPEER ELECTRONICS, INC. | RK73H1ETTP22R1F | 3 | G | R12,R13,R136 |  |  |  |  |  |  |
|  |  |  |  |  | 133 | 61011BH00-012-G |  | RES,22.1 Ohm,+/-1%,1/16W,G,SMD0402 | WALSIN TECHNOLOGY CORPORATION | WR04X22R1FTL |  | G |  |  |  |  |  |  |  |
|  |  |  |  |  | 133 | 61011BH00-011-G |  | RES,22.1 Ohm,+/-1%,1/16W,G,SMD0402 | YAGEO CORPORATION COMPONENT | RC0402FR-0722R1L |  | G |  |  |  |  |  |  |  |
|  |  |  |  |  | 133 | 61011BH00-044-G |  | RES,22.1 Ohm,+/-1%,1/16W,G,SMD0402 | TA-I TECHNOLOGY CO., LTD. | RM04FTN22R1 |  | G |  |  |  |  |  |  |  |
|  |  |  |  | 134 | 134 | 61011M600-017-G |  | RES,82.5 Ohm,+/-1%,1/16W,G,SMD0402 | KOA SPEER ELECTRONICS, INC. | RK73H1ETTP82R5F | 1 | G | R14 |  |  |  |  |  |  |
|  |  |  |  |  | 134 | 61011M600-011-G |  | RES,82.5 Ohm,+/-1%,1/16W,G,SMD0402 | YAGEO CORPORATION COMPONENT | RC0402FR-0782R5L |  | G |  |  |  |  |  |  |  |
|  |  |  |  |  | 134 | 61011M600-012-G |  | RES,82.5 Ohm,+/-1%,1/16W,G,SMD0402 | WALSIN TECHNOLOGY CORPORATION | WR04X82R5FTL |  | G |  |  |  |  |  |  |  |
|  |  |  |  | 135 | 135 | 610112W00-017-G |  | RES,2KOhm,+/-5%,1/16W,G,SMD0402 | KOA SPEER ELECTRONICS, INC. | RK73B1ETTP202J | 37 | G | R15,R17,R27,R29,R38,R39,R48,R49,R50,R51,R53,R54,R55,R57,R58,R59,R60,R61,R62,R63,R64,R65,R66,R67,R68,R69,R79,R80,R81,R82,R83,R87,R93,R95,R97,R98,R99 |  |  |  |  |  |  |
|  |  |  |  |  | 135 | 610112W00-012-G |  | RES,2KOhm,+/-5%,1/16W,G,SMD0402 | WALSIN TECHNOLOGY CORPORATION | WR04X202JTL |  | G |  |  |  |  |  |  |  |
|  |  |  |  |  | 135 | 610112W00-011-G |  | RES,2KOhm,+/-5%,1/16W,G,SMD0402 | YAGEO CORPORATION COMPONENT | RC0402JR-072KL |  | G |  |  |  |  |  |  |  |
|  |  |  |  |  | 135 | 610112W00-044-G |  | RES,2KOhm,+/-5%,1/16W,G,SMD0402 | TA-I TECHNOLOGY CO., LTD. | RM04JTN202 |  | G |  |  |  |  |  |  |  |
|  |  |  |  |  | 135 | 610112W00-024-G |  | RES,2KOhm,+/-5%,1/16W,G,SMD0402 | PANASONIC INDUSTRIAL CO.,LTD. | ERJ2GEJ202X |  | G |  |  |  |  |  |  |  |
|  |  |  |  | 136 | 136 | 610114E00-017-G |  | RES,33.2 Ohm,+/-1%,1/16W,G,SMD0402 | KOA SPEER ELECTRONICS, INC. | RK73H1ETTP33R2F | 1 | G | R16 |  |  |  |  |  |  |
|  |  |  |  |  | 136 | 610114E00-012-G |  | RES,33.2 Ohm,+/-1%,1/16W,G,SMD0402 | WALSIN TECHNOLOGY CORPORATION | WR04X33R2FTL |  | G |  |  |  |  |  |  |  |
|  |  |  |  |  | 136 | 610114E00-011-G |  | RES,33.2 Ohm,+/-1%,1/16W,G,SMD0402 | YAGEO CORPORATION COMPONENT | RC0402FR-0733R2L |  | G |  |  |  |  |  |  |  |
|  |  |  |  |  | 136 | 610114E00-044-G |  | RES,33.2 Ohm,+/-1%,1/16W,G,SMD0402 | TA-I TECHNOLOGY CO., LTD. | RM04FTN33R2 |  | G |  |  |  |  |  |  |  |
|  |  |  |  | 137 | 137 | 610114J00-017-G | - | RES,2KOhm,+/-1%,1/16W,G,SMD0402 | KOA SPEER ELECTRONICS, INC. | RK73H1ETTP2001F | 1 | G | R26 |  |  |  |  |  |  |
|  |  |  |  |  | 137 | 610114J00-012-G |  | RES,2KOhm,+/-1%,1/16W,G,SMD0402 | WALSIN TECHNOLOGY CORPORATION | WR04X2001FTL |  | G |  |  |  |  |  |  |  |
|  |  |  |  |  | 137 | 610114J00-011-G |  | RES,2KOhm,+/-1%,1/16W,G,SMD0402 | YAGEO CORPORATION COMPONENT | RC0402FR-072KL |  | G |  |  |  |  |  |  |  |
|  |  |  |  |  | 137 | 610114J00-044-G |  | RES,2KOhm,+/-1%,1/16W,G,SMD0402 | TA-I TECHNOLOGY CO., LTD. | RM04FTN2001 |  | G |  |  |  |  |  |  |  |
|  |  |  |  |  | 137 | 610114J00-024-G |  | RES,2KOhm,+/-1%,1/16W,G,SMD0402 | PANASONIC INDUSTRIAL CO.,LTD. | ERJ2RKF2001X |  | G |  |  |  |  |  |  |  |
|  |  |  |  |  | 137 | 610114J00-029-G |  | RES,2KOhm,+/-1%,1/16W,G,SMD0402 | VISHAY ENTER TECHNO LOGY.INC | CRCW04022K00FKED |  | G |  |  |  |  |  |  |  |
|  |  |  |  | 138 | 138 | 61010JY00-017-G | - | RES,220 Ohm,+/-5%,1/16W,G,SMD0402 | KOA SPEER ELECTRONICS, INC. | RK73B1ETTP221J | 5 | G | R192,R194,R200,R201,R203 |  |  |  |  |  |  |
|  |  |  |  |  | 138 | 61010JY00-012-G |  | RES,220 Ohm,+/-5%,1/16W,G,SMD0402 | WALSIN TECHNOLOGY CORPORATION | WR04X221JTL |  | G |  |  |  |  |  |  |  |
|  |  |  |  |  | 138 | 61010JY00-011-G |  | RES,220 Ohm,+/-5%,1/16W,G,SMD0402 | YAGEO CORPORATION COMPONENT | RC0402JR-07220RL |  | G |  |  |  |  |  |  |  |
|  |  |  |  |  | 138 | 61010JY00-044-G |  | RES,220 Ohm,+/-5%,1/16W,G,SMD0402 | TA-I TECHNOLOGY CO., LTD. | RM04JTN221 |  | G |  |  |  |  |  |  |  |
|  |  |  |  | 139 | 139 | 61012RW00-017-G |  | RES,510mOhm,+/-1%,1/8W,G,SMD0402 | KOA SPEER ELECTRONICS, INC. | SR731ETTPR510F | 12 | G | R115,R116,R117,R118,R119,R120,R121,R122,R123,R124,R125,R126 |  |  |  |  |  |  |
|  |  |  |  |  | 139 | 61012RW00-011-G |  | RES,510mOhm,+/-1%,1/8W,G,SMD0402 | YAGEO CORPORATION COMPONENT | PT0402FR-7W0R51L |  | G |  |  |  |  |  |  |  |
|  |  |  |  |  | 139 | 61012RW00-012-G |  | RES,510mOhm,+/-1%,1/8W,G,SMD0402 | WALSIN TECHNOLOGY CORPORATION | WW04PR510FTL |  | G |  |  |  |  |  |  |  |
|  |  |  |  | 140 | 140 | 61011T000-017-G |  | RES,82 Ohm,+/-1%,1/16W,G,SMD0402 | KOA SPEER ELECTRONICS, INC. | RK73H1ETTP82R0F | 42 | G | R143,R144,R145,R146,R147,R148,R149,R150,R151,R152,R153,R154,R155,R156,R157,R158,R159,R160,R161,R162,R163,R164,R165,R166,R167,R168,R169,R170,R171,R172,R173,R174,R175,R177,R178,R179,R180,R181,R182,R183,R184,R185 |  |  |  |  |  |  |
|  |  |  |  |  | 140 | 61011T000-011-G |  | RES,82 Ohm,+/-1%,1/16W,G,SMD0402 | YAGEO CORPORATION COMPONENT | RC0402FR-0782RL |  | G |  |  |  |  |  |  |  |
|  |  |  |  |  | 140 | 61011T000-012-G |  | RES,82 Ohm,+/-1%,1/16W,G,SMD0402 | WALSIN TECHNOLOGY CORPORATION | WR04X82R0FTL |  | G |  |  |  |  |  |  |  |
|  |  |  |  |  | 140 | 61011T000-044-G |  | RES,82 Ohm,+/-1%,1/16W,G,SMD0402 | TA-I TECHNOLOGY CO., LTD. | RM04FTN82R0 |  | G |  |  |  |  |  |  |  |
|  |  |  |  | 141 | 141 | 610101V00-017-G | K9572 | RES,22 Ohm,+/-5%,1/16W,G,SMD0402 | KOA SPEER ELECTRONICS, INC. | RK73B1ETTP220J | 1 | G | R190 |  |  |  |  |  |  |
|  |  |  |  |  | 141 | 610101V00-012-G |  | RES,22 Ohm,+/-5%,1/16W,G,SMD0402 | WALSIN TECHNOLOGY CORPORATION | WR04X220JTL |  | G |  |  |  |  |  |  |  |
|  |  |  |  |  | 141 | 610101V00-011-G |  | RES,22 Ohm,+/-5%,1/16W,G,SMD0402 | YAGEO CORPORATION COMPONENT | RC0402JR-0722RL |  | G |  |  |  |  |  |  |  |
|  |  |  |  |  | 141 | 610101V00-044-G |  | RES,22 Ohm,+/-5%,1/16W,G,SMD0402 | TA-I TECHNOLOGY CO., LTD. | RM04JTN220 |  | G |  |  |  |  |  |  |  |
|  |  |  |  |  | 141 | 610101V00-024-G |  | RES,22 Ohm,+/-5%,1/16W,G,SMD0402 | PANASONIC INDUSTRIAL CO.,LTD. | ERJ2GEJ220X |  | G |  |  |  |  |  |  |  |
|  |  |  |  | 142 | 142 | 61011H500-017-G | - | RES,22 Ohm,+/-1%,1/16W,G,SMD0402 | KOA SPEER ELECTRONICS, INC. | RK73H1ETTP22R0F | 1 | G | R202 |  |  |  |  |  |  |
|  |  |  |  |  | 142 | 61011H500-012-G |  | RES,22 Ohm,+/-1%,1/16W,G,SMD0402 | WALSIN TECHNOLOGY CORPORATION | WR04X22R0FTL |  | G |  |  |  |  |  |  |  |
|  |  |  |  |  | 142 | 61011H500-011-G |  | RES,22 Ohm,+/-1%,1/16W,G,SMD0402 | YAGEO CORPORATION COMPONENT | RC0402FR-0722RL |  | G |  |  |  |  |  |  |  |
|  |  |  |  |  | 142 | 61011H500-044-G |  | RES,22 Ohm,+/-1%,1/16W,G,SMD0402 | TA-I TECHNOLOGY CO., LTD. | RM04FTN22R0 |  | G |  |  |  |  |  |  |  |
|  |  |  |  |  | 142 | 61011H500-024-G |  | RES,22 Ohm,+/-1%,1/16W,G,SMD0402 | PANASONIC INDUSTRIAL CO.,LTD. | ERJ2RKF22R0X |  | G |  |  |  |  |  |  |  |
|  |  |  |  | 143 | 143 | 610100T00-017-G |  | RES,1KOhm,+/-5%,1/16W,G,SMD0402 | KOA SPEER ELECTRONICS, INC. | RK73B1ETTP102J | 7 | G | R208,R209,R218,R219,R224,R225,R1510 |  |  |  |  |  |  |
|  |  |  |  |  | 143 | 610100T00-012-G |  | RES,1KOhm,+/-5%,1/16W,G,SMD0402 | WALSIN TECHNOLOGY CORPORATION | WR04X102JTL |  | G |  |  |  |  |  |  |  |
|  |  |  |  |  | 143 | 610100T00-011-G |  | RES,1KOhm,+/-5%,1/16W,G,SMD0402 | YAGEO CORPORATION COMPONENT | RC0402JR-071KL |  | G |  |  |  |  |  |  |  |
|  |  |  |  |  | 143 | 610100T00-044-G |  | RES,1KOhm,+/-5%,1/16W,G,SMD0402 | TA-I TECHNOLOGY CO., LTD. | RM04JTN102 |  | G |  |  |  |  |  |  |  |
|  |  |  |  |  | 143 | 610100T00-024-G |  | RES,1KOhm,+/-5%,1/16W,G,SMD0402 | PANASONIC INDUSTRIAL CO.,LTD. | ERJ2GEJ102X |  | G |  |  |  |  |  |  |  |
|  |  |  |  | 144 | 144 | 610107B00-017-G | K9576 | RES,4.7KOhm,+/-5%,1/16W,G,SMD0402 | KOA SPEER ELECTRONICS, INC. | RK73B1ETTP472J | 4 | G | R228,R1415,R1440,R1517 |  |  |  |  |  |  |
|  |  |  |  |  | 144 | 610107B00-012-G |  | RES,4.7KOhm,+/-5%,1/16W,G,SMD0402 | WALSIN TECHNOLOGY CORPORATION | WR04X472JTL |  | G |  |  |  |  |  |  |  |
|  |  |  |  |  | 144 | 610107B00-011-G |  | RES,4.7KOhm,+/-5%,1/16W,G,SMD0402 | YAGEO CORPORATION COMPONENT | RC0402JR-074K7L |  | G |  |  |  |  |  |  |  |
|  |  |  |  |  | 144 | 610107B00-044-G |  | RES,4.7KOhm,+/-5%,1/16W,G,SMD0402 | TA-I TECHNOLOGY CO., LTD. | RM04JTN472 |  | G |  |  |  |  |  |  |  |
|  |  |  |  |  | 144 | 610107B00-024-G |  | RES,4.7KOhm,+/-5%,1/16W,G,SMD0402 | PANASONIC INDUSTRIAL CO.,LTD. | ERJ2GEJ472X |  | G |  |  |  |  |  |  |  |
|  |  |  |  |  | 144 | 610107B00-029-G |  | RES,4.7KOhm,+/-5%,1/16W,G,SMD0402 | VISHAY ENTER TECHNO LOGY.INC | CRCW04024K70JNED |  | G |  |  |  |  |  |  |  |
|  |  |  |  | 145 | 145 | 61010L100-017-G | - | RES,100KOhm,+/-1%,1/16W,G,SMD0402 | KOA SPEER ELECTRONICS, INC. | RK73H1ETTP1003F | 3 | G | R233,R238,R245 |  |  |  |  |  |  |
|  |  |  |  |  | 145 | 61010L100-012-G |  | RES,100KOhm,+/-1%,1/16W,G,SMD0402 | WALSIN TECHNOLOGY CORPORATION | WR04X1003FTL |  | G |  |  |  |  |  |  |  |
|  |  |  |  |  | 145 | 61010L100-011-G |  | RES,100KOhm,+/-1%,1/16W,G,SMD0402 | YAGEO CORPORATION COMPONENT | RC0402FR-07100KL |  | G |  |  |  |  |  |  |  |
|  |  |  |  |  | 145 | 61010L100-044-G |  | RES,100KOhm,+/-1%,1/16W,G,SMD0402 | TA-I TECHNOLOGY CO., LTD. | RM04FTN1003 |  | G |  |  |  |  |  |  |  |
|  |  |  |  |  | 145 | 61010L106-029-G |  | RES,100KOhm,+/-1%,1/16W,G,SMD0402 | VISHAY ENTER TECHNO LOGY.INC | CRCW0402100KFKEDC |  | G |  |  |  |  |  |  |  |
|  |  |  |  |  | 145 | 61010L100-024-G |  | RES,100KOhm,+/-1%,1/16W,G,SMD0402 | PANASONIC INDUSTRIAL CO.,LTD. | ERJ2RKF1003X |  | G |  |  |  |  |  |  |  |
|  |  |  |  | 146 | 146 | 61011WQ00-017-G | - | RES,3KOhm,+/-1%,1/16W,G,SMD0402 | KOA SPEER ELECTRONICS, INC. | RK73H1ETTP3001F | 56 | G | R255,R256,R257,R258,R259,R260,R261,R262,R263,R268,R269,R270,R271,R272,R273,R274,R275,R276,R281,R282,R283,R284,R285,R286,R287,R288,R289,R297,R298,R299,R300,R301,R302,R303,R304,R305,R310,R311,R312,R313,R314,R315,R316,R317,R318,R326,R327,R328,R329,R330,R331,R332,R333,R334,R383,R384 |  |  |  |  |  |  |
|  |  |  |  |  | 146 | 61011WQ00-012-G |  | RES,3KOhm,+/-1%,1/16W,G,SMD0402 | WALSIN TECHNOLOGY CORPORATION | WR04X3001FTL |  | G |  |  |  |  |  |  |  |
|  |  |  |  |  | 146 | 61011WQ00-011-G |  | RES,3KOhm,+/-1%,1/16W,G,SMD0402 | YAGEO CORPORATION COMPONENT | RC0402FR-073KL |  | G |  |  |  |  |  |  |  |
|  |  |  |  |  | 146 | 61011WQ00-044-G |  | RES,3KOhm,+/-1%,1/16W,G,SMD0402 | TA-I TECHNOLOGY CO., LTD. | RM04FTN3001 |  | G |  |  |  |  |  |  |  |
|  |  |  |  | 147 | 147 | 61011B000-017-G | - | RES,1.5KOhm,+/-1%,1/16W,G,SMD0402 | KOA SPEER ELECTRONICS, INC. | RK73H1ETTP1501F | 1 | G | R382 |  |  |  |  |  |  |
|  |  |  |  |  | 147 | 61011B000-012-G |  | RES,1.5KOhm,+/-1%,1/16W,G,SMD0402 | WALSIN TECHNOLOGY CORPORATION | WR04X1501FTL |  | G |  |  |  |  |  |  |  |
|  |  |  |  |  | 147 | 61011B000-011-G |  | RES,1.5KOhm,+/-1%,1/16W,G,SMD0402 | YAGEO CORPORATION COMPONENT | RC0402FR-071K5L |  | G |  |  |  |  |  |  |  |
|  |  |  |  |  | 147 | 61011B000-044-G |  | RES,1.5KOhm,+/-1%,1/16W,G,SMD0402 | TA-I TECHNOLOGY CO., LTD. | RM04FTN1501 |  | G |  |  |  |  |  |  |  |
|  |  |  |  |  | 147 | 61011B000-024-G |  | RES,1.5KOhm,+/-1%,1/16W,G,SMD0402 | PANASONIC INDUSTRIAL CO.,LTD. | ERJ2RKF1501X |  | G |  |  |  |  |  |  |  |
|  |  |  |  | 148 | 148 | 610102700-017-G | - | RES,49.9 Ohm,+/-1%,1/16W,G,SMD0402 | KOA SPEER ELECTRONICS, INC. | RK73H1ETTP49R9F | 2 | G | R445,R448 |  |  |  |  |  |  |
|  |  |  |  |  | 148 | 610102700-012-G |  | RES,49.9 Ohm,+/-1%,1/16W,G,SMD0402 | WALSIN TECHNOLOGY CORPORATION | WR04X49R9FTL |  | G |  |  |  |  |  |  |  |
|  |  |  |  |  | 148 | 610102700-011-G |  | RES,49.9 Ohm,+/-1%,1/16W,G,SMD0402 | YAGEO CORPORATION COMPONENT | RC0402FR-0749R9L |  | G |  |  |  |  |  |  |  |
|  |  |  |  |  | 148 | 610102700-044-G |  | RES,49.9 Ohm,+/-1%,1/16W,G,SMD0402 | TA-I TECHNOLOGY CO., LTD. | RM04FTN49R9 |  | G |  |  |  |  |  |  |  |
|  |  |  |  |  | 148 | 610102700-029-G |  | RES,49.9 Ohm,+/-1%,1/16W,G,SMD0402 | VISHAY ENTER TECHNO LOGY.INC | CRCW040249R9FKED |  | G |  |  |  |  |  |  |  |
|  |  |  |  |  | 148 | 610102700-024-G |  | RES,49.9 Ohm,+/-1%,1/16W,G,SMD0402 | PANASONIC INDUSTRIAL CO.,LTD. | ERJ2RKF49R9X |  | G |  |  |  |  |  |  |  |
|  |  |  |  | 149 | 149 | 610115J00-017-G | - | RES,33 Ohm,+/-1%,1/16W,G,SMD0402 | KOA SPEER ELECTRONICS, INC. | RK73H1ETTP33R0F | 2 | G | R446,R447 |  |  |  |  |  |  |
|  |  |  |  |  | 149 | 610115J00-012-G |  | RES,33 Ohm,+/-1%,1/16W,G,SMD0402 | WALSIN TECHNOLOGY CORPORATION | WR04X33R0FTL |  | G |  |  |  |  |  |  |  |
|  |  |  |  |  | 149 | 610115J00-011-G |  | RES,33 Ohm,+/-1%,1/16W,G,SMD0402 | YAGEO CORPORATION COMPONENT | RC0402FR-0733RL |  | G |  |  |  |  |  |  |  |
|  |  |  |  |  | 149 | 610115J00-044-G |  | RES,33 Ohm,+/-1%,1/16W,G,SMD0402 | TA-I TECHNOLOGY CO., LTD. | RM04FTN33R0 |  | G |  |  |  |  |  |  |  |
|  |  |  |  |  | 149 | 610115J00-024-G |  | RES,33 Ohm,+/-1%,1/16W,G,SMD0402 | PANASONIC INDUSTRIAL CO.,LTD. | ERJ2RKF33R0X |  | G |  |  |  |  |  |  |  |
|  |  |  |  | 150 | 150 | 61011T800-017-G | - | RES,240 Ohm,+/-1%,1/16W,G,SMD0402 | KOA SPEER ELECTRONICS, INC. | RK73H1ETTP2400F | 1 | G | R454 |  |  |  |  |  |  |
|  |  |  |  |  | 150 | 61011T800-012-G |  | RES,240 Ohm,+/-1%,1/16W,G,SMD0402 | WALSIN TECHNOLOGY CORPORATION | WR04X2400FTL |  | G |  |  |  |  |  |  |  |
|  |  |  |  |  | 150 | 61011T800-011-G |  | RES,240 Ohm,+/-1%,1/16W,G,SMD0402 | YAGEO CORPORATION COMPONENT | RC0402FR-07240RL |  | G |  |  |  |  |  |  |  |
|  |  |  |  |  | 150 | 61011T800-044-G |  | RES,240 Ohm,+/-1%,1/16W,G,SMD0402 | TA-I TECHNOLOGY CO., LTD. | RM04FTN2400 |  | G |  |  |  |  |  |  |  |
|  |  |  |  | 151 | 151 | 610112500-017-G | - | RES,475 Ohm,+/-1%,1/16W,G,SMD0402 | KOA SPEER ELECTRONICS, INC. | RK73H1ETTP4750F | 1 | G | R1411 |  |  |  |  |  |  |
|  |  |  |  |  | 151 | 610112500-012-G |  | RES,475 Ohm,+/-1%,1/16W,G,SMD0402 | WALSIN TECHNOLOGY CORPORATION | WR04X4750FTL |  | G |  |  |  |  |  |  |  |
|  |  |  |  |  | 151 | 610112500-011-G |  | RES,475 Ohm,+/-1%,1/16W,G,SMD0402 | YAGEO CORPORATION COMPONENT | RC0402FR-07475RL |  | G |  |  |  |  |  |  |  |
|  |  |  |  |  | 151 | 610112500-044-G |  | RES,475 Ohm,+/-1%,1/16W,G,SMD0402 | TA-I TECHNOLOGY CO., LTD. | RM04FTN4750 |  | G |  |  |  |  |  |  |  |
|  |  |  |  | 152 | 152 | 610107L00-017-G |  | RES,1 Ohm,+/-5%,1/10W,G,SMD0603 | KOA SPEER ELECTRONICS, INC. | RK73B1JTTD1R0J | 1 | G | R1413 |  |  |  |  |  |  |
|  |  |  |  |  | 152 | 610107L00-011-G |  | RES,1 Ohm,+/-5%,1/10W,G,SMD0603 | YAGEO CORPORATION COMPONENT | RC0603JR-071RL |  | G |  |  |  |  |  |  |  |
|  |  |  |  |  | 152 | 610107L00-012-G |  | RES,1 Ohm,+/-5%,1/10W,G,SMD0603 | WALSIN TECHNOLOGY CORPORATION | WR06X1R0JTL |  | G |  |  |  |  |  |  |  |
|  |  |  |  |  | 152 | 610107L00-044-G |  | RES,1 Ohm,+/-5%,1/10W,G,SMD0603 | TA-I TECHNOLOGY CO., LTD. | RM06JTN1R0 |  | G |  |  |  |  |  |  |  |
|  |  |  |  | 153 | 153 | 610107C00-017-G | K9577 | RES,10KOhm,+/-5%,1/16W,G,SMD0402 | KOA SPEER ELECTRONICS, INC. | RK73B1ETTP103J | 1 | G | R1426 |  |  |  |  |  |  |
|  |  |  |  |  | 153 | 610107C00-012-G |  | RES,10KOhm,+/-5%,1/16W,G,SMD0402 | WALSIN TECHNOLOGY CORPORATION | WR04X103JTL |  | G |  |  |  |  |  |  |  |
|  |  |  |  |  | 153 | 610107C00-011-G |  | RES,10KOhm,+/-5%,1/16W,G,SMD0402 | YAGEO CORPORATION COMPONENT | RC0402JR-0710KL |  | G |  |  |  |  |  |  |  |
|  |  |  |  |  | 153 | 610107C00-044-G |  | RES,10KOhm,+/-5%,1/16W,G,SMD0402 | TA-I TECHNOLOGY CO., LTD. | RM04JTN103 |  | G |  |  |  |  |  |  |  |
|  |  |  |  |  | 153 | 610107C00-024-G |  | RES,10KOhm,+/-5%,1/16W,G,SMD0402 | PANASONIC INDUSTRIAL CO.,LTD. | ERJ2GEJ103X |  | G |  |  |  |  |  |  |  |
|  |  |  |  |  | 153 | 610107C00-029-G |  | RES,10KOhm,+/-5%,1/16W,G,SMD0402 | VISHAY ENTER TECHNO LOGY.INC | CRCW040210K0JNED |  | G |  |  |  |  |  |  |  |
|  |  |  |  | 154 | 154 | 610118100-017-G | - | RES,1.4KOhm,+/-1%,1/16W,G,SMD0402 | KOA SPEER ELECTRONICS, INC. | RK73H1ETTP1401F | 4 | G | R1529,R1530,R1531,R1532 |  |  |  |  |  |  |
|  |  |  |  |  | 154 | 610118100-012-G |  | RES,1.4KOhm,+/-1%,1/16W,G,SMD0402 | WALSIN TECHNOLOGY CORPORATION | WR04X1401FTL |  | G |  |  |  |  |  |  |  |
|  |  |  |  |  | 154 | 610118100-011-G |  | RES,1.4KOhm,+/-1%,1/16W,G,SMD0402 | YAGEO CORPORATION COMPONENT | RC0402FR-071K4L |  | G |  |  |  |  |  |  |  |
|  |  |  |  |  | 154 | 610118100-044-G |  | RES,1.4KOhm,+/-1%,1/16W,G,SMD0402 | TA-I TECHNOLOGY CO., LTD | RM04FTN1401 |  | G |  |  |  |  |  |  |  |
|  |  |  |  |  | 154 | 610118100-024-G |  | RES,1.4KOhm,+/-1%,1/16W,G,SMD0402 | PANASONIC INDUSTRIAL CO.,LTD. | ERJ2RKF1401X |  | G |  |  |  |  |  |  |  |
|  |  |  |  | 155 | 155 | 21050LA00-217-G |  | IC,IDT,5V41234NLGI8,G,VFQFPN-16,SMD | INTEGRATED DEVICE TECHNOLOGY | 5V41234NLGI8 | 1 | G | U_CLKGEN |  |  |  |  |  |  |
|  |  |  |  | 156 | 156 | 410515T00-216-G |  | Flash,MT28EW128ABA1LJS-0SIT,2.7V~3.6V,128M,CFI,G,TSOP-56,SMD | MICRON TECHNOLOGY, INC. | MT28EW128ABA1LJS-0SIT | 1 | G | U_EXP_FLASH1 |  |  |  |  |  |  |
|  |  |  |  | 157 | 157 | 41040C200-223-G |  | EEPROM,CAT24C04WI-GT3,1.8~5.5V,4K,I2C,G,SOIC-8,SMD | ON SEMICONDUCTOR CORP | CAT24C04WI-GT3 | 1 | G | U_EXP_FRU1 |  |  |  |  |  |  |
|  |  |  |  | 158 | 158 | 410401W00-214-G |  | EEPROM,M24C02-WMN6TP,2.5~5.5V,256*8,I2C,G,SOIC-8,SMD | ST MICRO ELECTRONICS,INC | M24C02-WMN6TP | 1 | G | U_EXP_FRU2 |  |  |  |  |  |  |
|  |  |  |  | 159 | 159 | 420103G00-244-G | - | SRAM,CY14V101LA-BA45XIT,3.0~3.6V,1M,G,FBGA-48,SMD | CYPRESS SEMICONDUCTOR CORP | CY14V101LA-BA45XIT | 1 | G | U_EXP_NVSRAM1 |  |  |  |  |  |  |
|  |  |  |  | 160 | 160 | 311004800-031-G | - | IC,Translator,PCA9617ADPJ,0.8~5.5V,2.2~5.5V,G,TSSOP-8,SMD | NXP SEMICONDUCTORS | PCA9617ADPJ | 2 | G | U8,U_I2C_RE1 |  |  |  |  |  |  |
|  |  |  |  | 161 | 161 | 210826W00-283-G |  | IC,BROADCOM,PEX9797-AA80BCG,AA,G,FCBGA-1156,SMD | BROADCOM SINGAPORE PTE LTD. | SS14-0B00-00 | 1 | G | U_PEX_SW1 |  |  |  |  |  |  |
|  |  |  |  | 162 | 162 | 310103J00-223-G |  | IC,Gate&Inverter,NL17SZ08DFT2G,1.65~5.5V,G,SOT353-5,SMD | ON SEMICONDUCTOR CORP | NL17SZ08DFT2G | 2 | G | U2,U108 |  |  |  |  |  |  |
|  |  |  |  | 163 | 163 | 210828A00-GUW-G |  | IC,AVAGO,SX00-0B00-00,G,fpBGA-1197,SMD | AVAGO TECHNOLOGIES INTERNATION/AGILENT SEMICONDUCTOR | SX00-0B00-00 | 1 | G | U3 |  |  |  |  |  |  |
|  |  |  |  | 164 | 164 | 32020WJ00-183-G | - | IC,Power Controller,TPS3808G01DBVR,G,SOT23-6,SMD | TEXAS INSTRUMENTS | TPS3808G01DBVR | 1 | G | U4 |  |  |  |  |  |  |
|  |  |  |  | 165 | 165 | 32022NH00-252-G |  | IC,Power Controller,PT7M6315US29D1TBEX,G,SOT143-4,SMD | PERICOM SEMICONDUCTOR CORP | PT7M6315US29D1TBEX | 1 | G | U6 |  |  |  |  |  |  |
|  |  |  |  | 166 | 166 | 410409700-191-G | - | EEPROM,AT25256B-SSHL-T,1.8~5.5V,256K,SPI,G,SOIC-8,SMD | ATMEL CORPORATION | AT25256B-SSHL-T | 2 | G | U9,U117 |  |  |  |  |  |  |
|  |  |  |  | 167 | 167 | 310405F00-252-G |  | Logic IC,Multiplexer,PI3B3257LEX,2.97V~3.63V,0.25ns,TSSOP,16P,G | PERICOM SEMICONDUCTOR CORP | PI3B3257LEX | 1 | G | U27 |  |  |  |  |  |  |
|  |  |  |  | 168 | 168 | 310502800-031-G |  | IC,Buffer,74LVC1G07GW,1.65~5.5V,G,SOT353-5,SMD | NXP SEMICONDUCTORS | 74LVC1G07GW | 2 | G | U107,U110 |  |  |  |  |  |  |
|  |  |  |  | 169 | 169 | 310504B00-031-G |  | IC,Buffer,74LVC1G17GW,1.65~5.5V,G,SOT353-5,SMD | NXP SEMICONDUCTORS | 74LVC1G17GW | 1 | G | U109 |  |  |  |  |  |  |
|  |  |  |  | 170 | 170 | 710124Y00-100-G |  | XTAL,25MHz,+/-20ppm,20pF,G,SMD | TXC CORPORATION | 7M25020015 | 1 | G | X1 |  |  |  |  |  |  |
|  |  |  |  | 171 | 171 | 71020C800-162-G |  | OSC,150MHz,+/-50ppm,3.3V,50 Ohm,G,SMD | EPSON ELECTRONICS AMERICA,INC. | EG-2102CA 150.0000M-PGPAB | 1 | G | Y1 |  |  |  |  |  |  |
|  |  |  |  | 172 | 172 | U10-B274-250T |  | CONN,SAS,V/T,0.6mm,30u,G,SMD-74 | AMPHENOL SHANGHAI CORP. | U10-B274-250T | 12 | G | J_PCIE_OUT1,J_PCIE_IN1,J_PCIE_OUT2,J_PCIE_IN2,J_PCIE_OUT3,J_PCIE_OUT4,J4,J_PCIE_OUT5,J5,J_PCIE_OUT6,J6,J_PCIE_OUT7 |  |  |  |  |  |  |
|  |  |  |  | 173 | 173 | 34066Q200-317-G |  | CONN,Header,Power,2X8,V/T,Bla,3mm,G,DIP-16 | MOLEX INCORPORATED | 43045-1627 | 1 | G | J_PWR_BP |  |  |  |  |  |  |
|  |  |  |  | 174 | 174 | 340636700-600-G |  | CONN,Header,Power,2X8,V/T,Whi,4.2mm,G,DIP-16 | FOXCONN TECHNOLOGY CO.,LTD. | HM3508E-HP1 | 1 | G | J_PWR_IN |  |  |  |  |  |  |
|  |  |  |  | 175 | 175 | 340716800-245-G |  | CONN,SAS,V/T,Bla,0.75mm,30u,G,SMD-72 | AMPHENOL SHANGHAI CORP. | G40H4232212HR | 1 | G | J_SAS_IN1 |  |  |  |  |  |  |
|  |  |  |  | 176 | 176 | 340626400-600-G |  | CONN,Header,Shrouded,1X4,V/T,1mm,Ivo,G,SMD-4 | FOXCONN TECHNOLOGY CO.,LTD. | HS6104E | 2 | G | J_UART1,J_SMART1 |  |  |  |  |  |  |
|  |  |  |  | 177 | 177 | 3406ALW00-317-G |  | CONN,Header,Shrouded,2X5,V/T,Bla,2mm,30u,G,SMD-10 | MOLEX INCORPORATED | 87832-5423 | 1 | G | J3 |  |  |  |  |  |  |
|  |  |  |  | 178 | 178 | 34045GE00-GRS-G |  | CONN,SPI FLASH SOCKET,Bla,1.27mm,15u,G,SMD-8 | LOTES CO LTD | ASPI0001-P002A | 1 | G | U10 |  |  |  |  |  |  |
